FILE_TYPE = MACRO_DRAWING;
SET COLOR_WIRE YELLOW;
SET COLOR_PROP ORANGE;
SET COLOR_DOT WHITE;
SET COLOR_ARC YELLOW;
SET COLOR_BODY GREEN;
SET COLOR_NOTE PURPLE;
SET PROP_DISPLAY VALUE;
SET PAGE_NUMBER P285;
FORCEADD Q_CAP..1
(-10525 2200);
FORCEPROP 1 LAST PART_NUMBER CH5104KEB02
J 0
(-10475 2050);
DISPLAY 0.617021 (-10475 2050);
PAINT BLUE (-10475 2050);
DISPLAY INVISIBLE (-10475 2050);
FORCEPROP 1 LAST TOLERANCE 10%
J 0
(-10475 2150);
DISPLAY 0.617021 (-10475 2150);
PAINT SKYBLUE (-10475 2150);
FORCEPROP 1 LAST PACK_TYPE C0402
J 0
(-10475 2000);
DISPLAY 0.617021 (-10475 2000);
PAINT SKYBLUE (-10475 2000);
FORCEPROP 1 LAST VOLTAGE 25V
J 0
(-10475 2200);
DISPLAY 0.617021 (-10475 2200);
PAINT SKYBLUE (-10475 2200);
FORCEPROP 1 LAST MATERIAL X6S
J 0
(-10475 2100);
DISPLAY 0.617021 (-10475 2100);
PAINT SKYBLUE (-10475 2100);
FORCEPROP 1 LAST VALUE 1UF
J 0
(-10475 2250);
DISPLAY 0.617021 (-10475 2250);
PAINT SKYBLUE (-10475 2250);
FORCEPROP 1 LAST LOCATION PC644
J 0
(-10475 2300);
DISPLAY 0.617021 (-10475 2300);
PAINT AQUA (-10475 2300);
FORCEPROP 1 LASTPIN (-10525 2300) $PN 1
J 0
(-10515 2280);
DISPLAY 0.617021 (-10515 2280);
FORCEPROP 1 LASTPIN (-10525 2100) $PN 2
J 0
(-10515 2080);
DISPLAY 0.617021 (-10515 2080);
FORCEPROP 2 LAST CDS_LIB pure_quanta
J 0
(-10525 2200);
DISPLAY INVISIBLE (-10525 2200);
FORCEPROP 2 LAST SEC_TYPE C0402
J 0
(-10475 2400);
DISPLAY 1.021277 (-10475 2400);
DISPLAY INVISIBLE (-10475 2400);
FORCEPROP 2 LAST BOM_COST VR_PCH
J 0
(-10475 2350);
DISPLAY 0.680851 (-10475 2350);
DISPLAY INVISIBLE (-10475 2350);
FORCEPROP 1 LAST PATH I1
J 0
(-10475 2350);
DISPLAY 0.978723 (-10475 2350);
PAINT WHITE (-10475 2350);
DISPLAY INVISIBLE (-10475 2350);
FORCEPROP 2 LAST SEC 1
J 0
(-10475 2400);
DISPLAY 0.680851 (-10475 2400);
PAINT MONO (-10475 2400);
DISPLAY INVISIBLE (-10475 2400);
FORCEADD Q_RES..2
(-9175 2075);
FORCEPROP 1 LAST PART_NUMBER CS29762FB05
J 0
(-9135 1950);
DISPLAY 0.617021 (-9135 1950);
PAINT BLUE (-9135 1950);
DISPLAY INVISIBLE (-9135 1950);
FORCEPROP 1 LAST PACK_TYPE 0402LF
J 0
(-9135 1900);
DISPLAY 0.617021 (-9135 1900);
PAINT SKYBLUE (-9135 1900);
FORCEPROP 1 LAST MATERIAL CHIP
J 0
(-9135 2000);
DISPLAY 0.617021 (-9135 2000);
PAINT SKYBLUE (-9135 2000);
FORCEPROP 1 LAST TOLERANCE 1%
J 0
(-9130 2100);
DISPLAY 0.617021 (-9130 2100);
PAINT SKYBLUE (-9130 2100);
FORCEPROP 1 LAST WATTAGE 1/16W
J 0
(-9125 2050);
DISPLAY 0.617021 (-9125 2050);
PAINT SKYBLUE (-9125 2050);
FORCEPROP 1 LAST VALUE 9.76K
J 0
(-9130 2150);
DISPLAY 0.617021 (-9130 2150);
PAINT SKYBLUE (-9130 2150);
FORCEPROP 1 LAST LOCATION PR1339
J 0
(-9130 2200);
DISPLAY 0.617021 (-9130 2200);
PAINT AQUA (-9130 2200);
FORCEPROP 1 LASTPIN (-9175 2175) $PN 1
J 0
(-9170 2137);
DISPLAY 0.617021 (-9170 2137);
PAINT MONO (-9170 2137);
FORCEPROP 1 LASTPIN (-9175 1975) $PN 2
J 0
(-9170 1985);
DISPLAY 0.617021 (-9170 1985);
PAINT MONO (-9170 1985);
FORCEPROP 2 LAST CDS_LIB pure_quanta
J 0
(-9175 2075);
DISPLAY INVISIBLE (-9175 2075);
FORCEPROP 1 LAST PATH I10
J 0
(-9125 2250);
DISPLAY 0.978723 (-9125 2250);
PAINT WHITE (-9125 2250);
DISPLAY INVISIBLE (-9125 2250);
FORCEPROP 0 LAST $SEC 1
J 0
(-9125 2250);
DISPLAY 0.680851 (-9125 2250);
PAINT MONO (-9125 2250);
DISPLAY INVISIBLE (-9125 2250);
FORCEPROP 0 LAST CDS_SEC 1
J 0
(-9125 2250);
DISPLAY 1.021277 (-9125 2250);
DISPLAY INVISIBLE (-9125 2250);
FORCEADD Q_CAP..1
(-9750 2950);
FORCEPROP 1 LAST PART_NUMBER TMP_QCH21006JB10
J 2
(-9775 2800);
DISPLAY 0.510638 (-9775 2800);
DISPLAY INVISIBLE (-9775 2800);
FORCEPROP 1 LAST PACK_TYPE 0402
J 2
(-9775 2750);
DISPLAY 0.510638 (-9775 2750);
FORCEPROP 1 LAST VALUE 1000PF
J 2
(-9775 3000);
DISPLAY 0.510638 (-9775 3000);
FORCEPROP 1 LAST VOLTAGE 50V
J 2
(-9775 2950);
DISPLAY 0.510638 (-9775 2950);
FORCEPROP 1 LAST TOLERANCE 5%
J 2
(-9775 2900);
DISPLAY 0.510638 (-9775 2900);
FORCEPROP 1 LAST MATERIAL EMPTY
J 2
(-9775 2850);
DISPLAY 0.510638 (-9775 2850);
PAINT RED (-9775 2850);
FORCEPROP 1 LAST LOCATION C2445
J 2
(-9775 3050);
DISPLAY 0.510638 (-9775 3050);
FORCEPROP 1 LASTPIN (-9750 3050) $PN 1
J 0
(-9740 3030);
DISPLAY 0.787234 (-9740 3030);
PAINT MONO (-9740 3030);
FORCEPROP 1 LASTPIN (-9750 2850) $PN 2
J 0
(-9740 2830);
DISPLAY 0.787234 (-9740 2830);
PAINT MONO (-9740 2830);
FORCEPROP 2 LAST SEC_TYPE 0402
J 0
(-9700 3150);
DISPLAY 1.021277 (-9700 3150);
DISPLAY INVISIBLE (-9700 3150);
FORCEPROP 2 LAST CDS_LIB pure_quanta
J 0
(-9750 2950);
DISPLAY INVISIBLE (-9750 2950);
FORCEPROP 1 LAST PATH I11
J 0
(-9700 3100);
DISPLAY 0.978723 (-9700 3100);
PAINT WHITE (-9700 3100);
DISPLAY INVISIBLE (-9700 3100);
FORCEPROP 1 LAST LOCATION C2445
J 0
(-9800 3050);
DISPLAY 1.021277 (-9800 3050);
PAINT AQUA (-9800 3050);
DISPLAY INVISIBLE (-9800 3050);
FORCEPROP 2 LAST SEC 1
J 0
(-9700 3150);
DISPLAY 0.680851 (-9700 3150);
PAINT MONO (-9700 3150);
DISPLAY INVISIBLE (-9700 3150);
FORCEADD UNIVERSAL_GND..1
(-9650 2725);
FORCEPROP 3 LASTPIN (-9650 2775) SIG_NAME GND\g
J 0
(-9640 2785);
DISPLAY 0.659574 (-9640 2785);
PAINT MONO (-9640 2785);
DISPLAY INVISIBLE (-9640 2785);
FORCEPROP 1 LAST HDL_POWER GND
J 1
(-9625 2650);
DISPLAY 0.872340 (-9625 2650);
PAINT GREEN (-9625 2650);
DISPLAY INVISIBLE (-9625 2650);
FORCEPROP 2 LAST CDS_LIB logical_power
J 0
(-9650 2725);
PAINT MONO (-9650 2725);
DISPLAY INVISIBLE (-9650 2725);
FORCEPROP 1 LAST PATH I12
J 0
(-9575 2725);
DISPLAY 0.872340 (-9575 2725);
PAINT AQUA (-9575 2725);
DISPLAY INVISIBLE (-9575 2725);
FORCEADD Q_RES..2
(-9650 2950);
FORCEPROP 1 LAST PART_NUMBER CS22002FB07
J 0
(-9610 2825);
DISPLAY 0.617021 (-9610 2825);
PAINT BLUE (-9610 2825);
DISPLAY INVISIBLE (-9610 2825);
FORCEPROP 1 LAST WATTAGE 1/16W
J 0
(-9610 2925);
DISPLAY 0.617021 (-9610 2925);
PAINT SKYBLUE (-9610 2925);
FORCEPROP 1 LAST TOLERANCE 1%
J 0
(-9605 2975);
DISPLAY 0.617021 (-9605 2975);
PAINT SKYBLUE (-9605 2975);
FORCEPROP 1 LAST MATERIAL CHIP
J 0
(-9610 2875);
DISPLAY 0.617021 (-9610 2875);
PAINT SKYBLUE (-9610 2875);
FORCEPROP 1 LAST VALUE 2K
J 0
(-9605 3025);
DISPLAY 0.617021 (-9605 3025);
PAINT SKYBLUE (-9605 3025);
FORCEPROP 1 LAST PACK_TYPE 0402LF
J 0
(-9610 2775);
DISPLAY 0.617021 (-9610 2775);
PAINT SKYBLUE (-9610 2775);
FORCEPROP 1 LAST LOCATION R2374
J 0
(-9605 3075);
DISPLAY 0.723404 (-9605 3075);
PAINT AQUA (-9605 3075);
FORCEPROP 1 LASTPIN (-9650 3050) $PN 1
J 0
(-9645 3012);
DISPLAY 0.617021 (-9645 3012);
FORCEPROP 1 LASTPIN (-9650 2850) $PN 2
J 0
(-9645 2860);
DISPLAY 0.617021 (-9645 2860);
FORCEPROP 2 LAST CDS_LIB pure_quanta
J 0
(-9650 2950);
PAINT MONO (-9650 2950);
DISPLAY INVISIBLE (-9650 2950);
FORCEPROP 1 LAST PATH I13
J 0
(-9600 3125);
DISPLAY 0.978723 (-9600 3125);
PAINT WHITE (-9600 3125);
DISPLAY INVISIBLE (-9600 3125);
FORCEPROP 2 LAST $SEC 1
J 0
(-9600 3175);
DISPLAY 0.680851 (-9600 3175);
PAINT MONO (-9600 3175);
DISPLAY INVISIBLE (-9600 3175);
FORCEPROP 2 LAST CDS_SEC 1
J 0
(-9600 3175);
DISPLAY 1.021277 (-9600 3175);
DISPLAY INVISIBLE (-9600 3175);
FORCEADD Q_RES..1
(-10325 3350);
FORCEPROP 1 LAST PART_NUMBER CS31002FB08
J 0
(-10475 3425);
DISPLAY 0.617021 (-10475 3425);
PAINT BLUE (-10475 3425);
DISPLAY INVISIBLE (-10475 3425);
FORCEPROP 1 LAST MATERIAL EMPTY
J 0
(-10075 3350);
DISPLAY 0.617021 (-10075 3350);
PAINT RED (-10075 3350);
FORCEPROP 1 LAST TOLERANCE 1%
J 0
(-10150 3350);
DISPLAY 0.617021 (-10150 3350);
PAINT SKYBLUE (-10150 3350);
FORCEPROP 1 LAST VALUE 10K
J 2
(-10175 3350);
DISPLAY 0.617021 (-10175 3350);
PAINT SKYBLUE (-10175 3350);
FORCEPROP 1 LAST PACK_TYPE 0402LF
J 0
(-10475 3475);
DISPLAY 0.617021 (-10475 3475);
PAINT SKYBLUE (-10475 3475);
FORCEPROP 1 LAST WATTAGE 1/16W
J 2
(-10075 3475);
DISPLAY 0.617021 (-10075 3475);
PAINT SKYBLUE (-10075 3475);
FORCEPROP 1 LAST LOCATION R2367
J 0
(-10575 3350);
DISPLAY 0.723404 (-10575 3350);
PAINT AQUA (-10575 3350);
FORCEPROP 1 LASTPIN (-10425 3350) $PN 1
J 0
(-10413 3362);
DISPLAY 0.617021 (-10413 3362);
FORCEPROP 1 LASTPIN (-10225 3350) $PN 2
J 0
(-10263 3362);
DISPLAY 0.617021 (-10263 3362);
FORCEPROP 2 LAST CDS_LIB pure_quanta
J 0
(-10325 3350);
PAINT MONO (-10325 3350);
DISPLAY INVISIBLE (-10325 3350);
FORCEPROP 1 LAST PATH I14
J 0
(-10375 3500);
DISPLAY 0.978723 (-10375 3500);
PAINT WHITE (-10375 3500);
DISPLAY INVISIBLE (-10375 3500);
FORCEPROP 2 LAST $SEC 1
J 0
(-10375 3550);
DISPLAY 0.680851 (-10375 3550);
PAINT MONO (-10375 3550);
DISPLAY INVISIBLE (-10375 3550);
FORCEPROP 2 LAST CDS_SEC 1
J 0
(-10375 3550);
DISPLAY 1.021277 (-10375 3550);
DISPLAY INVISIBLE (-10375 3550);
FORCEADD Q_CAP..1
(-10350 3900);
FORCEPROP 1 LAST PART_NUMBER CH6223MEA01
J 0
(-10300 3700);
DISPLAY 0.617021 (-10300 3700);
PAINT BLUE (-10300 3700);
DISPLAY INVISIBLE (-10300 3700);
FORCEPROP 1 LAST VOLTAGE 16V
J 0
(-10300 3900);
DISPLAY 0.617021 (-10300 3900);
PAINT SKYBLUE (-10300 3900);
FORCEPROP 1 LAST MATERIAL X6S
J 0
(-10300 3800);
DISPLAY 0.617021 (-10300 3800);
PAINT SKYBLUE (-10300 3800);
FORCEPROP 1 LAST TOLERANCE 20%
J 0
(-10300 3850);
DISPLAY 0.617021 (-10300 3850);
PAINT SKYBLUE (-10300 3850);
FORCEPROP 1 LAST VALUE 22UF
J 0
(-10300 3950);
DISPLAY 0.617021 (-10300 3950);
PAINT SKYBLUE (-10300 3950);
FORCEPROP 1 LAST PACK_TYPE C0805
J 0
(-10300 3750);
DISPLAY 0.617021 (-10300 3750);
PAINT SKYBLUE (-10300 3750);
FORCEPROP 1 LAST LOCATION PC1260
J 0
(-10300 4000);
DISPLAY 0.617021 (-10300 4000);
PAINT AQUA (-10300 4000);
FORCEPROP 1 LASTPIN (-10350 4000) $PN 1
J 0
(-10340 3980);
DISPLAY 0.617021 (-10340 3980);
PAINT MONO (-10340 3980);
FORCEPROP 1 LASTPIN (-10350 3800) $PN 2
J 0
(-10340 3780);
DISPLAY 0.617021 (-10340 3780);
PAINT MONO (-10340 3780);
FORCEPROP 2 LAST BOM_COST VR_PCH
J 0
(-10300 4050);
DISPLAY 0.680851 (-10300 4050);
DISPLAY INVISIBLE (-10300 4050);
FORCEPROP 2 LAST CDS_LIB pure_quanta
J 0
(-10350 3900);
DISPLAY INVISIBLE (-10350 3900);
FORCEPROP 1 LAST PATH I15
J 0
(-10300 4050);
DISPLAY 0.978723 (-10300 4050);
PAINT WHITE (-10300 4050);
DISPLAY INVISIBLE (-10300 4050);
FORCEPROP 2 LAST $SEC 1
J 0
(-10300 4100);
DISPLAY 0.680851 (-10300 4100);
PAINT MONO (-10300 4100);
DISPLAY INVISIBLE (-10300 4100);
FORCEPROP 2 LAST CDS_SEC 1
J 0
(-10300 4100);
DISPLAY 1.021277 (-10300 4100);
DISPLAY INVISIBLE (-10300 4100);
FORCEADD Q_CAP..1
(-9925 3900);
FORCEPROP 1 LAST PART_NUMBER CH6223MEA01
J 0
(-9875 3700);
DISPLAY 0.617021 (-9875 3700);
PAINT BLUE (-9875 3700);
DISPLAY INVISIBLE (-9875 3700);
FORCEPROP 1 LAST TOLERANCE 20%
J 0
(-9875 3850);
DISPLAY 0.617021 (-9875 3850);
PAINT SKYBLUE (-9875 3850);
FORCEPROP 1 LAST MATERIAL X6S
J 0
(-9875 3800);
DISPLAY 0.617021 (-9875 3800);
PAINT SKYBLUE (-9875 3800);
FORCEPROP 1 LAST VALUE 22UF
J 0
(-9875 3950);
DISPLAY 0.617021 (-9875 3950);
PAINT SKYBLUE (-9875 3950);
FORCEPROP 1 LAST VOLTAGE 16V
J 0
(-9875 3900);
DISPLAY 0.617021 (-9875 3900);
PAINT SKYBLUE (-9875 3900);
FORCEPROP 1 LAST PACK_TYPE C0805
J 0
(-9875 3750);
DISPLAY 0.617021 (-9875 3750);
PAINT SKYBLUE (-9875 3750);
FORCEPROP 1 LAST LOCATION PC1261
J 0
(-9875 4000);
DISPLAY 0.617021 (-9875 4000);
PAINT AQUA (-9875 4000);
FORCEPROP 1 LASTPIN (-9925 4000) $PN 1
J 0
(-9915 3980);
DISPLAY 0.617021 (-9915 3980);
PAINT MONO (-9915 3980);
FORCEPROP 1 LASTPIN (-9925 3800) $PN 2
J 0
(-9915 3780);
DISPLAY 0.617021 (-9915 3780);
PAINT MONO (-9915 3780);
FORCEPROP 2 LAST BOM_COST VR_PCH
J 0
(-9875 4050);
DISPLAY 0.680851 (-9875 4050);
DISPLAY INVISIBLE (-9875 4050);
FORCEPROP 2 LAST CDS_LIB pure_quanta
J 0
(-9925 3900);
DISPLAY INVISIBLE (-9925 3900);
FORCEPROP 1 LAST PATH I16
J 0
(-9875 4050);
DISPLAY 0.978723 (-9875 4050);
PAINT WHITE (-9875 4050);
DISPLAY INVISIBLE (-9875 4050);
FORCEPROP 2 LAST $SEC 1
J 0
(-9875 4100);
DISPLAY 0.680851 (-9875 4100);
PAINT MONO (-9875 4100);
DISPLAY INVISIBLE (-9875 4100);
FORCEPROP 2 LAST CDS_SEC 1
J 0
(-9875 4100);
DISPLAY 1.021277 (-9875 4100);
DISPLAY INVISIBLE (-9875 4100);
FORCEADD Q_CAP..1
(-9500 3900);
FORCEPROP 1 LAST PART_NUMBER CH5103KEB01
J 0
(-9450 3750);
DISPLAY 0.617021 (-9450 3750);
PAINT BLUE (-9450 3750);
DISPLAY INVISIBLE (-9450 3750);
FORCEPROP 1 LAST PACK_TYPE C0402
J 0
(-9450 3700);
DISPLAY 0.617021 (-9450 3700);
PAINT SKYBLUE (-9450 3700);
FORCEPROP 1 LAST VALUE 1UF
J 0
(-9450 3950);
DISPLAY 0.617021 (-9450 3950);
PAINT SKYBLUE (-9450 3950);
FORCEPROP 1 LAST MATERIAL X6S
J 0
(-9450 3800);
DISPLAY 0.617021 (-9450 3800);
PAINT SKYBLUE (-9450 3800);
FORCEPROP 1 LAST VOLTAGE 16V
J 0
(-9450 3900);
DISPLAY 0.617021 (-9450 3900);
PAINT SKYBLUE (-9450 3900);
FORCEPROP 1 LAST TOLERANCE 10%
J 0
(-9450 3850);
DISPLAY 0.617021 (-9450 3850);
PAINT SKYBLUE (-9450 3850);
FORCEPROP 1 LAST LOCATION PC1262
J 0
(-9450 4000);
DISPLAY 0.617021 (-9450 4000);
PAINT AQUA (-9450 4000);
FORCEPROP 1 LASTPIN (-9500 4000) $PN 1
J 0
(-9490 3980);
DISPLAY 0.617021 (-9490 3980);
PAINT MONO (-9490 3980);
FORCEPROP 1 LASTPIN (-9500 3800) $PN 2
J 0
(-9490 3780);
DISPLAY 0.617021 (-9490 3780);
PAINT MONO (-9490 3780);
FORCEPROP 2 LAST CDS_LIB pure_quanta
J 0
(-9500 3900);
DISPLAY INVISIBLE (-9500 3900);
FORCEPROP 1 LAST PATH I17
J 0
(-9450 4050);
DISPLAY 0.978723 (-9450 4050);
PAINT WHITE (-9450 4050);
DISPLAY INVISIBLE (-9450 4050);
FORCEPROP 2 LAST $SEC 1
J 0
(-9450 4100);
DISPLAY 0.680851 (-9450 4100);
PAINT MONO (-9450 4100);
DISPLAY INVISIBLE (-9450 4100);
FORCEPROP 2 LAST CDS_SEC 1
J 0
(-9450 4100);
DISPLAY 1.021277 (-9450 4100);
DISPLAY INVISIBLE (-9450 4100);
FORCEADD Q_RES..1
(-8950 2900);
FORCEPROP 1 LAST PART_NUMBER CS33012FB03
J 0
(-8900 2850);
DISPLAY 0.638298 (-8900 2850);
DISPLAY INVISIBLE (-8900 2850);
FORCEPROP 1 LAST VALUE 30.1K
J 2
(-9050 2925);
DISPLAY 0.638298 (-9050 2925);
FORCEPROP 1 LAST PACK_TYPE 0402LF
J 0
(-8900 2800);
DISPLAY 0.638298 (-8900 2800);
FORCEPROP 1 LAST MATERIAL CHIP
J 0
(-9075 2850);
DISPLAY 0.638298 (-9075 2850);
FORCEPROP 1 LAST WATTAGE 1/16W
J 2
(-8925 2800);
DISPLAY 0.638298 (-8925 2800);
FORCEPROP 1 LAST TOLERANCE 1%
J 0
(-8825 2925);
DISPLAY 0.638298 (-8825 2925);
FORCEPROP 1 LAST LOCATION PR3336
J 0
(-9250 2850);
DISPLAY 0.638298 (-9250 2850);
FORCEPROP 1 LASTPIN (-9050 2900) $PN 1
J 0
(-9038 2912);
DISPLAY 0.787234 (-9038 2912);
PAINT MONO (-9038 2912);
FORCEPROP 1 LASTPIN (-8850 2900) $PN 2
J 0
(-8888 2912);
DISPLAY 0.787234 (-8888 2912);
PAINT MONO (-8888 2912);
FORCEPROP 2 LAST CDS_LIB pure_quanta
J 0
(-8950 2900);
DISPLAY INVISIBLE (-8950 2900);
FORCEPROP 1 LAST PATH I18
J 0
(-9000 3050);
DISPLAY 0.978723 (-9000 3050);
PAINT WHITE (-9000 3050);
DISPLAY INVISIBLE (-9000 3050);
FORCEPROP 0 LAST $SEC 1
J 0
(-8825 2975);
DISPLAY 0.680851 (-8825 2975);
PAINT MONO (-8825 2975);
DISPLAY INVISIBLE (-8825 2975);
FORCEPROP 0 LAST CDS_SEC 1
J 0
(-8825 2975);
DISPLAY 1.021277 (-8825 2975);
DISPLAY INVISIBLE (-8825 2975);
FORCEADD UNIVERSAL_GND..1
(-8525 2800);
FORCEPROP 3 LASTPIN (-8525 2850) SIG_NAME GND\g
J 0
(-8515 2860);
DISPLAY 0.659574 (-8515 2860);
PAINT MONO (-8515 2860);
DISPLAY INVISIBLE (-8515 2860);
FORCEPROP 1 LAST HDL_POWER GND
J 1
(-8500 2725);
DISPLAY 0.872340 (-8500 2725);
PAINT GREEN (-8500 2725);
DISPLAY INVISIBLE (-8500 2725);
FORCEPROP 2 LAST CDS_LIB logical_power
J 0
(-8525 2800);
DISPLAY INVISIBLE (-8525 2800);
FORCEPROP 1 LAST PATH I19
J 0
(-8450 2800);
DISPLAY 0.872340 (-8450 2800);
PAINT AQUA (-8450 2800);
DISPLAY INVISIBLE (-8450 2800);
FORCEADD UNIVERSAL_GND..1
(-10525 1925);
FORCEPROP 3 LASTPIN (-10525 1975) SIG_NAME GND\g
J 0
(-10515 1985);
DISPLAY 0.659574 (-10515 1985);
PAINT MONO (-10515 1985);
DISPLAY INVISIBLE (-10515 1985);
FORCEPROP 1 LAST HDL_POWER GND
J 1
(-10500 1850);
DISPLAY 0.872340 (-10500 1850);
PAINT GREEN (-10500 1850);
DISPLAY INVISIBLE (-10500 1850);
FORCEPROP 2 LAST CDS_LIB logical_power
J 0
(-10525 1925);
DISPLAY INVISIBLE (-10525 1925);
FORCEPROP 1 LAST PATH I2
J 0
(-10450 1925);
DISPLAY 0.872340 (-10450 1925);
PAINT AQUA (-10450 1925);
DISPLAY INVISIBLE (-10450 1925);
FORCEADD VCCAUX15..1
(-10800 4350);
FORCEPROP 3 LASTPIN (-10800 4300) SIG_NAME SW_P12V_PVCCIN_CPU1_FLT\g
J 0
(-10790 4310);
DISPLAY 0.659574 (-10790 4310);
PAINT MONO (-10790 4310);
DISPLAY INVISIBLE (-10790 4310);
FORCEPROP 1 LAST HDL_POWER SW_P12V_PVCCIN_CPU1_FLT
J 1
(-10800 4392);
DISPLAY 0.617021 (-10800 4392);
PAINT GREEN (-10800 4392);
FORCEPROP 2 LAST BOM_COST VR_PCH
J 0
(-10800 4425);
DISPLAY 0.680851 (-10800 4425);
DISPLAY INVISIBLE (-10800 4425);
FORCEPROP 2 LAST CDS_LIB logical_power
J 0
(-10800 4350);
DISPLAY INVISIBLE (-10800 4350);
FORCEPROP 1 LAST PATH I20
J 0
(-10750 4375);
DISPLAY 0.872340 (-10750 4375);
PAINT AQUA (-10750 4375);
DISPLAY INVISIBLE (-10750 4375);
FORCEADD UNIVERSAL_GND..1
(-7500 2025);
FORCEPROP 3 LASTPIN (-7500 2075) SIG_NAME GND\g
J 0
(-7490 2085);
DISPLAY 0.659574 (-7490 2085);
PAINT MONO (-7490 2085);
DISPLAY INVISIBLE (-7490 2085);
FORCEPROP 1 LAST HDL_POWER GND
J 1
(-7475 1950);
DISPLAY 0.872340 (-7475 1950);
PAINT GREEN (-7475 1950);
DISPLAY INVISIBLE (-7475 1950);
FORCEPROP 2 LAST CDS_LIB logical_power
J 0
(-7500 2025);
DISPLAY INVISIBLE (-7500 2025);
FORCEPROP 1 LAST PATH I21
J 0
(-7425 2025);
DISPLAY 0.872340 (-7425 2025);
PAINT AQUA (-7425 2025);
DISPLAY INVISIBLE (-7425 2025);
FORCEADD UNIVERSAL_GND..1
(-7350 1875);
FORCEPROP 3 LASTPIN (-7350 1925) SIG_NAME GND\g
J 0
(-7340 1935);
DISPLAY 0.659574 (-7340 1935);
PAINT MONO (-7340 1935);
DISPLAY INVISIBLE (-7340 1935);
FORCEPROP 1 LAST HDL_POWER GND
J 1
(-7325 1800);
DISPLAY 0.872340 (-7325 1800);
PAINT GREEN (-7325 1800);
DISPLAY INVISIBLE (-7325 1800);
FORCEPROP 2 LAST CDS_LIB logical_power
J 0
(-7350 1875);
DISPLAY INVISIBLE (-7350 1875);
FORCEPROP 1 LAST PATH I22
J 0
(-7275 1875);
DISPLAY 0.872340 (-7275 1875);
PAINT AQUA (-7275 1875);
DISPLAY INVISIBLE (-7275 1875);
FORCEADD Q_CAP..1
(-7350 2125);
FORCEPROP 1 LAST PART_NUMBER TMP_QCH32203KB11
J 0
(-7300 1975);
DISPLAY 0.510638 (-7300 1975);
DISPLAY INVISIBLE (-7300 1975);
FORCEPROP 1 LAST VALUE 0.022UF
J 0
(-7300 2175);
DISPLAY 0.638298 (-7300 2175);
FORCEPROP 1 LAST MATERIAL X7R
J 0
(-7300 2025);
DISPLAY 0.638298 (-7300 2025);
FORCEPROP 1 LAST VOLTAGE 16V
J 0
(-7300 2125);
DISPLAY 0.638298 (-7300 2125);
FORCEPROP 1 LAST PACK_TYPE 0402
J 0
(-7300 1925);
DISPLAY 0.638298 (-7300 1925);
FORCEPROP 1 LAST TOLERANCE 10%
J 0
(-7300 2075);
DISPLAY 0.638298 (-7300 2075);
FORCEPROP 1 LAST LOCATION PC2002
J 0
(-7300 2225);
DISPLAY 0.978723 (-7300 2225);
FORCEPROP 2 LAST CDS_LIB pure_quanta
J 0
(-7350 2125);
DISPLAY INVISIBLE (-7350 2125);
FORCEPROP 1 LAST PATH I23
J 0
(-7300 2275);
DISPLAY 0.978723 (-7300 2275);
PAINT WHITE (-7300 2275);
DISPLAY INVISIBLE (-7300 2275);
FORCEPROP 0 LAST $SEC 1
J 0
(-7300 2275);
DISPLAY INVISIBLE (-7300 2275);
FORCEPROP 0 LAST CDS_SEC 1
J 0
(-7300 2275);
DISPLAY INVISIBLE (-7300 2275);
FORCEPROP 1 LASTPIN (-7350 2225) $PN 1
J 0
(-7340 2205);
DISPLAY 0.787234 (-7340 2205);
PAINT MONO (-7340 2205);
DISPLAY INVISIBLE (-7340 2205);
FORCEPROP 1 LASTPIN (-7350 2025) $PN 2
J 0
(-7340 2005);
DISPLAY 0.787234 (-7340 2005);
PAINT MONO (-7340 2005);
DISPLAY INVISIBLE (-7340 2005);
FORCEADD Q_CAP..1
(-6850 2000);
FORCEPROP 1 LAST PART_NUMBER CH4104K1B00
J 0
(-6800 1850);
DISPLAY 0.617021 (-6800 1850);
PAINT BLUE (-6800 1850);
DISPLAY INVISIBLE (-6800 1850);
FORCEPROP 1 LAST MATERIAL X7R
J 0
(-6800 1900);
DISPLAY 0.617021 (-6800 1900);
PAINT SKYBLUE (-6800 1900);
FORCEPROP 1 LAST VALUE 0.1UF
J 0
(-6800 2050);
DISPLAY 0.617021 (-6800 2050);
PAINT SKYBLUE (-6800 2050);
FORCEPROP 1 LAST VOLTAGE 25V
J 0
(-6800 2000);
DISPLAY 0.617021 (-6800 2000);
PAINT SKYBLUE (-6800 2000);
FORCEPROP 1 LAST PACK_TYPE 0402
J 0
(-6800 1800);
DISPLAY 0.617021 (-6800 1800);
PAINT SKYBLUE (-6800 1800);
FORCEPROP 1 LAST TOLERANCE 10%
J 0
(-6800 1950);
DISPLAY 0.617021 (-6800 1950);
PAINT SKYBLUE (-6800 1950);
FORCEPROP 1 LAST LOCATION PC1264
J 0
(-6800 2100);
DISPLAY 0.617021 (-6800 2100);
PAINT AQUA (-6800 2100);
FORCEPROP 1 LASTPIN (-6850 2100) $PN 1
J 0
(-6840 2080);
DISPLAY 0.617021 (-6840 2080);
PAINT MONO (-6840 2080);
FORCEPROP 1 LASTPIN (-6850 1900) $PN 2
J 0
(-6840 1880);
DISPLAY 0.617021 (-6840 1880);
PAINT MONO (-6840 1880);
FORCEPROP 2 LAST CDS_LIB pure_quanta
J 0
(-6850 2000);
DISPLAY INVISIBLE (-6850 2000);
FORCEPROP 1 LAST PATH I24
J 0
(-6800 2150);
DISPLAY 0.978723 (-6800 2150);
PAINT WHITE (-6800 2150);
DISPLAY INVISIBLE (-6800 2150);
FORCEPROP 2 LAST $SEC 1
J 0
(-6800 2200);
DISPLAY 0.680851 (-6800 2200);
PAINT MONO (-6800 2200);
DISPLAY INVISIBLE (-6800 2200);
FORCEPROP 2 LAST CDS_SEC 1
J 0
(-6800 2200);
DISPLAY 1.021277 (-6800 2200);
DISPLAY INVISIBLE (-6800 2200);
FORCEADD RS53318LR..1
(-8000 3000);
FORCEPROP 1 LAST PART_NUMBER AL053318002
J 0
(-8250 3850);
DISPLAY 0.723404 (-8250 3850);
PAINT GREEN (-8250 3850);
DISPLAY INVISIBLE (-8250 3850);
FORCEPROP 1 LAST MATERIAL IC
J 0
(-8245 3757);
DISPLAY 0.723404 (-8245 3757);
PAINT GREEN (-8245 3757);
FORCEPROP 2 LAST VALUE RS53318LR
J 0
(-8250 3925);
DISPLAY 0.617021 (-8250 3925);
PAINT SKYBLUE (-8250 3925);
FORCEPROP 2 LAST PART_TYPE SMLF
J 0
(-8250 3975);
DISPLAY 0.638298 (-8250 3975);
FORCEPROP 1 LAST LOCATION PU80
J 0
(-8245 4031);
DISPLAY 0.723404 (-8245 4031);
PAINT GREEN (-8245 4031);
FORCEPROP 2 LASTPIN (-7600 2325) $PN 2
J 0
(-7590 2335);
DISPLAY 0.680851 (-7590 2335);
PAINT MONO (-7590 2335);
FORCEPROP 2 LASTPIN (-7600 3475) $PN 1
J 0
(-7590 3485);
DISPLAY 0.680851 (-7590 3485);
PAINT MONO (-7590 3485);
FORCEPROP 2 LASTPIN (-8400 2375) $PN 3
J 2
(-8410 2385);
DISPLAY 0.680851 (-8410 2385);
PAINT MONO (-8410 2385);
FORCEPROP 2 LASTPIN (-8400 3175) $PN 8
J 2
(-8410 3185);
DISPLAY 0.680851 (-8410 3185);
PAINT MONO (-8410 3185);
FORCEPROP 2 LASTPIN (-7600 2725) $PN 7
J 0
(-7590 2735);
DISPLAY 0.680851 (-7590 2735);
PAINT MONO (-7590 2735);
FORCEPROP 2 LASTPIN (-8400 2975) $PN 4
J 2
(-8410 2985);
DISPLAY 0.680851 (-8410 2985);
PAINT MONO (-8410 2985);
FORCEPROP 2 LASTPIN (-7600 2375) $PN 11_18
J 0
(-7590 2385);
DISPLAY 0.680851 (-7590 2385);
PAINT MONO (-7590 2385);
FORCEPROP 2 LASTPIN (-7600 3675) $PN 9
J 0
(-7590 3685);
DISPLAY 0.680851 (-7590 3685);
PAINT MONO (-7590 3685);
FORCEPROP 2 LASTPIN (-7600 2475) $PN 5
J 0
(-7590 2485);
DISPLAY 0.680851 (-7590 2485);
PAINT MONO (-7590 2485);
FORCEPROP 2 LASTPIN (-7600 2575) $PN 6
J 0
(-7590 2585);
DISPLAY 0.680851 (-7590 2585);
PAINT MONO (-7590 2585);
FORCEPROP 2 LASTPIN (-7600 3175) $PN 20
J 0
(-7590 3185);
DISPLAY 0.680851 (-7590 3185);
PAINT MONO (-7590 3185);
FORCEPROP 2 LASTPIN (-8400 2725) $PN 19
J 2
(-8410 2735);
DISPLAY 0.680851 (-8410 2735);
PAINT MONO (-8410 2735);
FORCEPROP 2 LASTPIN (-8400 3675) $PN 10
J 2
(-8410 3685);
DISPLAY 0.680851 (-8410 3685);
PAINT MONO (-8410 3685);
FORCEPROP 2 LASTPIN (-8400 3625) $PN 21
J 2
(-8410 3635);
DISPLAY 0.680851 (-8410 3635);
PAINT MONO (-8410 3635);
FORCEPROP 2 LAST SEC_TYPE 
J 0
(-8225 4075);
DISPLAY 1.021277 (-8225 4075);
DISPLAY INVISIBLE (-8225 4075);
FORCEPROP 2 LAST CDS_LIB pure_quanta
J 0
(-8000 3000);
DISPLAY INVISIBLE (-8000 3000);
FORCEPROP 1 LAST NEEDS_NO_SIZE TRUE
J 0
(-8000 3000);
DISPLAY 0.723404 (-8000 3000);
PAINT GREEN (-8000 3000);
DISPLAY INVISIBLE (-8000 3000);
FORCEPROP 1 LAST CDS_LMAN_SYM_OUTLINE -250,725,250,-725
J 0
(-8000 3000);
DISPLAY 0.468085 (-8000 3000);
PAINT GREEN (-8000 3000);
DISPLAY INVISIBLE (-8000 3000);
FORCEPROP 1 LAST PATH I25
J 0
(-8000 3000);
DISPLAY 0.723404 (-8000 3000);
PAINT GREEN (-8000 3000);
DISPLAY INVISIBLE (-8000 3000);
FORCEPROP 2 LAST SEC 1
J 0
(-8225 4075);
DISPLAY 0.680851 (-8225 4075);
PAINT MONO (-8225 4075);
DISPLAY INVISIBLE (-8225 4075);
FORCEADD Q_CAP..1
(-6725 3400);
FORCEPROP 1 LAST PART_NUMBER CH4224K1B01
J 0
(-6675 3250);
DISPLAY 0.617021 (-6675 3250);
PAINT BLUE (-6675 3250);
DISPLAY INVISIBLE (-6675 3250);
FORCEPROP 1 LAST VALUE 0.22UF
J 0
(-6675 3450);
DISPLAY 0.617021 (-6675 3450);
PAINT SKYBLUE (-6675 3450);
FORCEPROP 1 LAST VOLTAGE 25V
J 0
(-6675 3400);
DISPLAY 0.617021 (-6675 3400);
PAINT SKYBLUE (-6675 3400);
FORCEPROP 1 LAST PACK_TYPE C0402
J 0
(-6675 3200);
DISPLAY 0.617021 (-6675 3200);
PAINT SKYBLUE (-6675 3200);
FORCEPROP 1 LAST TOLERANCE 10%
J 0
(-6675 3350);
DISPLAY 0.617021 (-6675 3350);
PAINT SKYBLUE (-6675 3350);
FORCEPROP 1 LAST MATERIAL X7R
J 0
(-6675 3300);
DISPLAY 0.617021 (-6675 3300);
PAINT SKYBLUE (-6675 3300);
FORCEPROP 1 LAST LOCATION PC1265
J 0
(-6675 3500);
DISPLAY 0.617021 (-6675 3500);
PAINT AQUA (-6675 3500);
FORCEPROP 1 LASTPIN (-6725 3500) $PN 1
J 0
(-6715 3480);
DISPLAY 0.617021 (-6715 3480);
PAINT MONO (-6715 3480);
FORCEPROP 1 LASTPIN (-6725 3300) $PN 2
J 0
(-6715 3280);
DISPLAY 0.617021 (-6715 3280);
PAINT MONO (-6715 3280);
FORCEPROP 2 LAST CDS_LIB pure_quanta
J 0
(-6725 3400);
DISPLAY INVISIBLE (-6725 3400);
FORCEPROP 1 LAST PATH I26
J 0
(-6675 3550);
DISPLAY 0.978723 (-6675 3550);
PAINT WHITE (-6675 3550);
DISPLAY INVISIBLE (-6675 3550);
FORCEPROP 2 LAST $SEC 1
J 0
(-6675 3600);
DISPLAY 0.680851 (-6675 3600);
PAINT MONO (-6675 3600);
DISPLAY INVISIBLE (-6675 3600);
FORCEPROP 2 LAST CDS_SEC 1
J 0
(-6675 3600);
DISPLAY 1.021277 (-6675 3600);
DISPLAY INVISIBLE (-6675 3600);
FORCEADD Q_RES..2
(-6600 4200);
FORCEPROP 1 LAST PART_NUMBER CS31002FB08
J 0
(-6560 4075);
DISPLAY 0.617021 (-6560 4075);
PAINT BLUE (-6560 4075);
DISPLAY INVISIBLE (-6560 4075);
FORCEPROP 1 LAST TOLERANCE 1%
J 0
(-6555 4225);
DISPLAY 0.617021 (-6555 4225);
PAINT SKYBLUE (-6555 4225);
FORCEPROP 1 LAST MATERIAL CHIP
J 0
(-6560 4125);
DISPLAY 0.617021 (-6560 4125);
PAINT SKYBLUE (-6560 4125);
FORCEPROP 1 LAST PACK_TYPE 0402LF
J 0
(-6560 4025);
DISPLAY 0.617021 (-6560 4025);
PAINT SKYBLUE (-6560 4025);
FORCEPROP 1 LAST WATTAGE 1/16W
J 0
(-6560 4175);
DISPLAY 0.617021 (-6560 4175);
PAINT SKYBLUE (-6560 4175);
FORCEPROP 1 LAST VALUE 10K
J 0
(-6555 4275);
DISPLAY 0.617021 (-6555 4275);
PAINT SKYBLUE (-6555 4275);
FORCEPROP 1 LAST LOCATION R2583
J 0
(-6555 4325);
DISPLAY 0.617021 (-6555 4325);
PAINT AQUA (-6555 4325);
FORCEPROP 1 LASTPIN (-6600 4300) $PN 1
J 0
(-6595 4262);
DISPLAY 0.617021 (-6595 4262);
FORCEPROP 1 LASTPIN (-6600 4100) $PN 2
J 0
(-6595 4110);
DISPLAY 0.617021 (-6595 4110);
FORCEPROP 2 LAST CDS_LIB pure_quanta
J 0
(-6600 4200);
DISPLAY INVISIBLE (-6600 4200);
FORCEPROP 2 LAST BOM_COST VR_PCH
J 0
(-6550 4375);
DISPLAY 0.680851 (-6550 4375);
DISPLAY INVISIBLE (-6550 4375);
FORCEPROP 1 LAST PATH I27
J 0
(-6550 4375);
DISPLAY 0.978723 (-6550 4375);
PAINT WHITE (-6550 4375);
DISPLAY INVISIBLE (-6550 4375);
FORCEPROP 0 LAST $SEC 1
J 0
(-6550 4425);
DISPLAY 0.680851 (-6550 4425);
PAINT MONO (-6550 4425);
DISPLAY INVISIBLE (-6550 4425);
FORCEPROP 0 LAST CDS_SEC 1
J 0
(-6550 4425);
DISPLAY 0.680851 (-6550 4425);
DISPLAY INVISIBLE (-6550 4425);
FORCEADD Q_RES..2
(-6375 2000);
FORCEPROP 1 LAST PART_NUMBER CS31132BB02
J 0
(-6335 1875);
DISPLAY 0.510638 (-6335 1875);
DISPLAY INVISIBLE (-6335 1875);
FORCEPROP 1 LAST PACK_TYPE 0402LF
J 0
(-6335 1825);
DISPLAY 0.510638 (-6335 1825);
FORCEPROP 1 LAST VALUE 11.3K
J 0
(-6330 2075);
DISPLAY 0.510638 (-6330 2075);
FORCEPROP 1 LAST TOLERANCE 0.1%
J 0
(-6330 2025);
DISPLAY 0.510638 (-6330 2025);
FORCEPROP 1 LAST WATTAGE 1/16W
J 0
(-6335 1975);
DISPLAY 0.510638 (-6335 1975);
FORCEPROP 1 LAST MATERIAL CHIP
J 0
(-6335 1925);
DISPLAY 0.510638 (-6335 1925);
FORCEPROP 1 LAST LOCATION PR1314
J 0
(-6330 2125);
DISPLAY 0.510638 (-6330 2125);
FORCEPROP 1 LASTPIN (-6375 2100) $PN 1
J 0
(-6370 2062);
DISPLAY 0.787234 (-6370 2062);
PAINT MONO (-6370 2062);
FORCEPROP 1 LASTPIN (-6375 1900) $PN 2
J 0
(-6370 1910);
DISPLAY 0.787234 (-6370 1910);
PAINT MONO (-6370 1910);
FORCEPROP 2 LAST CDS_LIB pure_quanta
J 0
(-6375 2000);
DISPLAY INVISIBLE (-6375 2000);
FORCEPROP 2 LAST BOM_COST VR_PCH
J 0
(-6325 2175);
DISPLAY 0.680851 (-6325 2175);
DISPLAY INVISIBLE (-6325 2175);
FORCEPROP 1 LAST PATH I28
J 0
(-6325 2175);
DISPLAY 0.978723 (-6325 2175);
PAINT WHITE (-6325 2175);
DISPLAY INVISIBLE (-6325 2175);
FORCEPROP 0 LAST $SEC 1
J 0
(-6325 2150);
DISPLAY 0.680851 (-6325 2150);
PAINT MONO (-6325 2150);
DISPLAY INVISIBLE (-6325 2150);
FORCEPROP 2 LAST CDS_SEC 1
J 0
(-6325 2225);
DISPLAY 0.680851 (-6325 2225);
DISPLAY INVISIBLE (-6325 2225);
FORCEADD MOSFET_N..1
R 2
(-5625 1800);
FORCEPROP 1 LAST PART_NUMBER BAM138K0000
J 2
(-5772 1711);
DISPLAY 0.617021 (-5772 1711);
PAINT BLUE (-5772 1711);
DISPLAY INVISIBLE (-5772 1711);
FORCEPROP 1 LAST MATERIAL EMPTY
J 2
(-5772 1631);
DISPLAY 0.617021 (-5772 1631);
PAINT RED (-5772 1631);
FORCEPROP 1 LAST VALUE BSS138K
J 2
(-5772 1871);
DISPLAY 0.617021 (-5772 1871);
PAINT SKYBLUE (-5772 1871);
FORCEPROP 2 LAST PATH I29
J 0
(-5750 1900);
DISPLAY 1.021277 (-5750 1900);
FORCEPROP 1 LAST LOCATION PU174
J 2
(-5772 1791);
DISPLAY 0.723404 (-5772 1791);
PAINT AQUA (-5772 1791);
FORCEPROP 1 LASTPIN (-5675 1900) $PN D
R 1
J 0
(-5675 1893);
DISPLAY 0.617021 (-5675 1893);
PAINT GREEN (-5675 1893);
FORCEPROP 1 LASTPIN (-5525 1700) $PN G
J 0
(-5535 1703);
DISPLAY 0.617021 (-5535 1703);
PAINT GREEN (-5535 1703);
FORCEPROP 1 LASTPIN (-5675 1600) $PN S
R 1
J 2
(-5675 1613);
DISPLAY 0.617021 (-5675 1613);
PAINT GREEN (-5675 1613);
FORCEPROP 0 LAST MANUF_PN BSS138K
J 2
(-5800 1675);
DISPLAY 0.808511 (-5800 1675);
DISPLAY INVISIBLE (-5800 1675);
FORCEPROP 1 LAST CDS_LMAN_SYM_OUTLINE -50,50,100,-150
J 2
(-5625 1800);
DISPLAY 0.468085 (-5625 1800);
PAINT GREEN (-5625 1800);
DISPLAY INVISIBLE (-5625 1800);
FORCEPROP 2 LAST CDS_LIB pure_quanta
J 2
(-5625 1800);
PAINT MONO (-5625 1800);
DISPLAY INVISIBLE (-5625 1800);
FORCEPROP 1 LAST PACK_TYPE SMLF
J 2
(-5650 1550);
DISPLAY 0.723404 (-5650 1550);
PAINT SKYBLUE (-5650 1550);
DISPLAY INVISIBLE (-5650 1550);
FORCEPROP 2 LAST $SEC 1
J 0
(-5750 1950);
DISPLAY 0.680851 (-5750 1950);
PAINT MONO (-5750 1950);
DISPLAY INVISIBLE (-5750 1950);
FORCEPROP 2 LAST CDS_SEC 1
J 0
(-5750 1950);
DISPLAY 1.021277 (-5750 1950);
DISPLAY INVISIBLE (-5750 1950);
FORCEADD Q_RES..2
(-10525 2650);
FORCEPROP 1 LAST PART_NUMBER CS00002JB13
J 0
(-10485 2525);
DISPLAY 0.617021 (-10485 2525);
PAINT BLUE (-10485 2525);
DISPLAY INVISIBLE (-10485 2525);
FORCEPROP 1 LAST PACK_TYPE 0402LF
J 0
(-10485 2475);
DISPLAY 0.617021 (-10485 2475);
PAINT SKYBLUE (-10485 2475);
FORCEPROP 1 LAST VALUE 0
J 0
(-10480 2725);
DISPLAY 0.617021 (-10480 2725);
PAINT SKYBLUE (-10480 2725);
FORCEPROP 1 LAST TOLERANCE 5%
J 0
(-10480 2675);
DISPLAY 0.617021 (-10480 2675);
PAINT SKYBLUE (-10480 2675);
FORCEPROP 1 LAST WATTAGE 1/16W
J 0
(-10485 2625);
DISPLAY 0.617021 (-10485 2625);
PAINT SKYBLUE (-10485 2625);
FORCEPROP 1 LAST MATERIAL CHIP
J 0
(-10485 2575);
DISPLAY 0.617021 (-10485 2575);
PAINT SKYBLUE (-10485 2575);
FORCEPROP 1 LAST LOCATION PR1338
J 0
(-10480 2775);
DISPLAY 0.617021 (-10480 2775);
PAINT AQUA (-10480 2775);
FORCEPROP 1 LASTPIN (-10525 2750) $PN 1
J 0
(-10520 2712);
DISPLAY 0.617021 (-10520 2712);
FORCEPROP 1 LASTPIN (-10525 2550) $PN 2
J 0
(-10520 2560);
DISPLAY 0.617021 (-10520 2560);
FORCEPROP 2 LAST CDS_LIB pure_quanta
J 0
(-10525 2650);
PAINT MONO (-10525 2650);
DISPLAY INVISIBLE (-10525 2650);
FORCEPROP 1 LAST PATH I3
J 0
(-10475 2825);
DISPLAY 0.978723 (-10475 2825);
PAINT WHITE (-10475 2825);
DISPLAY INVISIBLE (-10475 2825);
FORCEPROP 2 LAST $SEC 1
J 0
(-10475 2875);
DISPLAY 0.680851 (-10475 2875);
PAINT MONO (-10475 2875);
DISPLAY INVISIBLE (-10475 2875);
FORCEPROP 2 LAST CDS_SEC 1
J 0
(-10475 2875);
DISPLAY 1.021277 (-10475 2875);
DISPLAY INVISIBLE (-10475 2875);
FORCEADD Q_RES..1
(-5700 2025);
FORCEPROP 1 LAST PART_NUMBER CS32612BB02
J 0
(-5875 2075);
DISPLAY 0.617021 (-5875 2075);
PAINT BLUE (-5875 2075);
DISPLAY INVISIBLE (-5875 2075);
FORCEPROP 1 LAST MATERIAL EMPTY
J 0
(-5875 2125);
DISPLAY 0.617021 (-5875 2125);
PAINT RED (-5875 2125);
FORCEPROP 1 LAST VALUE 26.1K
J 2
(-5375 2050);
DISPLAY 0.617021 (-5375 2050);
PAINT SKYBLUE (-5375 2050);
FORCEPROP 1 LAST PACK_TYPE 0402LF
J 0
(-5700 2125);
DISPLAY 0.617021 (-5700 2125);
PAINT SKYBLUE (-5700 2125);
FORCEPROP 1 LAST WATTAGE 1/16W
J 2
(-5375 2125);
DISPLAY 0.617021 (-5375 2125);
PAINT SKYBLUE (-5375 2125);
FORCEPROP 1 LAST TOLERANCE 0.1%
J 0
(-5350 2050);
DISPLAY 0.617021 (-5350 2050);
PAINT SKYBLUE (-5350 2050);
FORCEPROP 1 LAST LOCATION PR2381
J 0
(-6000 2025);
DISPLAY 0.723404 (-6000 2025);
PAINT AQUA (-6000 2025);
FORCEPROP 1 LASTPIN (-5800 2025) $PN 1
J 0
(-5788 2037);
DISPLAY 0.617021 (-5788 2037);
FORCEPROP 1 LASTPIN (-5600 2025) $PN 2
J 0
(-5638 2037);
DISPLAY 0.617021 (-5638 2037);
FORCEPROP 2 LAST CDS_LIB pure_quanta
J 0
(-5700 2025);
PAINT MONO (-5700 2025);
DISPLAY INVISIBLE (-5700 2025);
FORCEPROP 1 LAST PATH I30
J 0
(-5750 2175);
DISPLAY 0.978723 (-5750 2175);
PAINT WHITE (-5750 2175);
DISPLAY INVISIBLE (-5750 2175);
FORCEPROP 2 LAST $SEC 1
J 0
(-5750 2225);
DISPLAY 0.680851 (-5750 2225);
PAINT MONO (-5750 2225);
DISPLAY INVISIBLE (-5750 2225);
FORCEPROP 2 LAST CDS_SEC 1
J 0
(-5750 2225);
DISPLAY 1.021277 (-5750 2225);
DISPLAY INVISIBLE (-5750 2225);
FORCEADD OFFPAGE..4
(-4875 1700);
FORCEPROP 2 LAST $XR1 281 
J 0
(-4569 1700);
DISPLAY 0.638298 (-4569 1700);
PAINT MONO (-4569 1700);
FORCEPROP 2 LAST $XR0 215 
J 0
(-4689 1700);
DISPLAY 0.638298 (-4689 1700);
PAINT MONO (-4689 1700);
FORCEPROP 1 LAST COMMENT_BODY TRUE
J 0
(-4900 1600);
DISPLAY 0.872340 (-4900 1600);
PAINT GREEN (-4900 1600);
DISPLAY INVISIBLE (-4900 1600);
FORCEPROP 1 LAST OFFPAGE TRUE
J 0
(-4550 1575);
DISPLAY 0.872340 (-4550 1575);
PAINT GREEN (-4550 1575);
DISPLAY INVISIBLE (-4550 1575);
FORCEPROP 2 LAST CDS_LIB standard
J 0
(-4875 1700);
PAINT MONO (-4875 1700);
DISPLAY INVISIBLE (-4875 1700);
FORCEPROP 2 LAST PATH I31
J 0
(-4550 1750);
DISPLAY 1.021277 (-4550 1750);
DISPLAY INVISIBLE (-4550 1750);
FORCEADD Q_CAP..1
(-4400 1925);
FORCEPROP 1 LAST PART_NUMBER TMP_QCH31004KB17
J 0
(-4350 1775);
DISPLAY 0.617021 (-4350 1775);
PAINT BLUE (-4350 1775);
DISPLAY INVISIBLE (-4350 1775);
FORCEPROP 1 LAST PACK_TYPE 0402
J 0
(-4350 1725);
DISPLAY 0.617021 (-4350 1725);
PAINT SKYBLUE (-4350 1725);
FORCEPROP 1 LAST MATERIAL X7R
J 0
(-4350 1825);
DISPLAY 0.617021 (-4350 1825);
PAINT RED (-4350 1825);
FORCEPROP 1 LAST TOLERANCE 10%
J 0
(-4350 1875);
DISPLAY 0.617021 (-4350 1875);
PAINT SKYBLUE (-4350 1875);
FORCEPROP 1 LAST VOLTAGE 25V
J 0
(-4350 1925);
DISPLAY 0.617021 (-4350 1925);
PAINT SKYBLUE (-4350 1925);
FORCEPROP 1 LAST VALUE 0.01UF
J 0
(-4350 1975);
DISPLAY 0.617021 (-4350 1975);
PAINT SKYBLUE (-4350 1975);
FORCEPROP 1 LAST LOCATION PC2282
J 0
(-4350 2025);
DISPLAY 0.617021 (-4350 2025);
PAINT AQUA (-4350 2025);
FORCEPROP 1 LASTPIN (-4400 2025) $PN 1
J 0
(-4390 2005);
DISPLAY 0.787234 (-4390 2005);
PAINT MONO (-4390 2005);
FORCEPROP 1 LASTPIN (-4400 1825) $PN 2
J 0
(-4390 1805);
DISPLAY 0.787234 (-4390 1805);
PAINT MONO (-4390 1805);
FORCEPROP 2 LAST CDS_LIB pure_quanta
J 0
(-4400 1925);
DISPLAY INVISIBLE (-4400 1925);
FORCEPROP 1 LAST PATH I32
J 0
(-4350 2075);
DISPLAY 0.978723 (-4350 2075);
PAINT WHITE (-4350 2075);
DISPLAY INVISIBLE (-4350 2075);
FORCEPROP 0 LAST $SEC 1
J 0
(-4350 2075);
DISPLAY 0.680851 (-4350 2075);
PAINT MONO (-4350 2075);
DISPLAY INVISIBLE (-4350 2075);
FORCEPROP 0 LAST CDS_SEC 1
J 0
(-4350 2075);
DISPLAY 1.021277 (-4350 2075);
DISPLAY INVISIBLE (-4350 2075);
FORCEADD Q_INDUCTOR..1
(-5900 3200);
FORCEPROP 1 LAST PART_NUMBER CV+68F5MZ05
J 0
(-6025 3310);
DISPLAY 0.617021 (-6025 3310);
PAINT BLUE (-6025 3310);
DISPLAY INVISIBLE (-6025 3310);
FORCEPROP 2 LAST VALUE 0.68UH
J 0
(-6025 3375);
DISPLAY 0.617021 (-6025 3375);
PAINT SKYBLUE (-6025 3375);
FORCEPROP 1 LAST MATERIAL IND
J 0
(-6025 3255);
DISPLAY 0.617021 (-6025 3255);
PAINT SKYBLUE (-6025 3255);
FORCEPROP 2 LAST PACK_TYPE SMLF
J 0
(-6025 3425);
DISPLAY 0.617021 (-6025 3425);
PAINT SKYBLUE (-6025 3425);
FORCEPROP 1 LAST LOCATION PL119
J 0
(-6200 3185);
DISPLAY 0.617021 (-6200 3185);
PAINT AQUA (-6200 3185);
FORCEPROP 2 LASTPIN (-6000 3175) $PN 1
J 2
(-6010 3185);
DISPLAY 0.617021 (-6010 3185);
FORCEPROP 2 LASTPIN (-5800 3175) $PN 2
J 0
(-5790 3185);
DISPLAY 0.617021 (-5790 3185);
FORCEPROP 2 LAST BOM_COST VR_PCH
J 0
(-6025 3500);
DISPLAY 0.680851 (-6025 3500);
DISPLAY INVISIBLE (-6025 3500);
FORCEPROP 1 LAST NEEDS_NO_SIZE TRUE
J 0
(-5900 3200);
DISPLAY 0.468085 (-5900 3200);
PAINT GREEN (-5900 3200);
DISPLAY INVISIBLE (-5900 3200);
FORCEPROP 2 LAST CDS_LIB pure_quanta
J 0
(-5900 3200);
PAINT MONO (-5900 3200);
DISPLAY INVISIBLE (-5900 3200);
FORCEPROP 1 LAST PATH I33
J 0
(-5825 3255);
DISPLAY 0.723404 (-5825 3255);
PAINT GREEN (-5825 3255);
DISPLAY INVISIBLE (-5825 3255);
FORCEPROP 2 LAST $SEC 1
J 0
(-6025 3475);
DISPLAY 0.680851 (-6025 3475);
PAINT MONO (-6025 3475);
DISPLAY INVISIBLE (-6025 3475);
FORCEPROP 2 LAST CDS_SEC 1
J 0
(-6025 3475);
DISPLAY 1.021277 (-6025 3475);
DISPLAY INVISIBLE (-6025 3475);
FORCEADD Q_RES..1
(-5700 2425);
FORCEPROP 1 LAST PART_NUMBER CS33832BB06
J 0
(-5800 2500);
DISPLAY 0.319149 (-5800 2500);
DISPLAY INVISIBLE (-5800 2500);
FORCEPROP 1 LAST TOLERANCE 0.1%
J 0
(-5800 2550);
DISPLAY 0.404255 (-5800 2550);
FORCEPROP 1 LAST PACK_TYPE 0402LF
J 0
(-5675 2550);
DISPLAY 0.404255 (-5675 2550);
FORCEPROP 1 LAST MATERIAL CHIP
J 0
(-5800 2525);
DISPLAY 0.404255 (-5800 2525);
FORCEPROP 1 LAST VALUE 38.3K
J 2
(-5500 2425);
DISPLAY 0.404255 (-5500 2425);
FORCEPROP 1 LAST WATTAGE 1/16W
J 2
(-5525 2500);
DISPLAY 0.404255 (-5525 2500);
FORCEPROP 1 LAST LOCATION PR1340
J 0
(-5900 2425);
DISPLAY 0.319149 (-5900 2425);
FORCEPROP 1 LASTPIN (-5800 2425) $PN 1
J 0
(-5788 2437);
DISPLAY 0.787234 (-5788 2437);
PAINT MONO (-5788 2437);
FORCEPROP 1 LASTPIN (-5600 2425) $PN 2
J 0
(-5638 2437);
DISPLAY 0.787234 (-5638 2437);
PAINT MONO (-5638 2437);
FORCEPROP 2 LAST CDS_LIB pure_quanta
J 0
(-5700 2425);
DISPLAY INVISIBLE (-5700 2425);
FORCEPROP 1 LAST PATH I34
J 0
(-5750 2575);
DISPLAY 0.978723 (-5750 2575);
PAINT WHITE (-5750 2575);
DISPLAY INVISIBLE (-5750 2575);
FORCEPROP 0 LAST $SEC 1
J 0
(-5675 2575);
DISPLAY 0.680851 (-5675 2575);
PAINT MONO (-5675 2575);
DISPLAY INVISIBLE (-5675 2575);
FORCEPROP 2 LAST CDS_SEC 1
J 0
(-5750 2625);
DISPLAY 1.021277 (-5750 2625);
DISPLAY INVISIBLE (-5750 2625);
FORCEADD Q_CAP..2
(-5700 2250);
FORCEPROP 1 LAST PART_NUMBER TMP_QCH16806KB17
J 1
(-5700 2325);
DISPLAY 0.617021 (-5700 2325);
PAINT BLUE (-5700 2325);
DISPLAY INVISIBLE (-5700 2325);
FORCEPROP 1 LAST VALUE 680PF
J 2
(-5425 2250);
DISPLAY 0.617021 (-5425 2250);
PAINT SKYBLUE (-5425 2250);
FORCEPROP 1 LAST TOLERANCE 10%
J 2
(-5325 2250);
DISPLAY 0.617021 (-5325 2250);
PAINT SKYBLUE (-5325 2250);
FORCEPROP 1 LAST MATERIAL X7R
J 0
(-5875 2375);
DISPLAY 0.617021 (-5875 2375);
PAINT SKYBLUE (-5875 2375);
FORCEPROP 1 LAST PACK_TYPE 0402
J 1
(-5675 2375);
DISPLAY 0.617021 (-5675 2375);
PAINT SKYBLUE (-5675 2375);
FORCEPROP 1 LAST VOLTAGE 50V
J 0
(-5575 2375);
DISPLAY 0.617021 (-5575 2375);
PAINT SKYBLUE (-5575 2375);
FORCEPROP 1 LAST LOCATION PC1266
J 1
(-5925 2250);
DISPLAY 0.617021 (-5925 2250);
PAINT AQUA (-5925 2250);
FORCEPROP 1 LASTPIN (-5800 2250) $PN 1
J 0
(-5810 2265);
DISPLAY 0.617021 (-5810 2265);
PAINT MONO (-5810 2265);
FORCEPROP 1 LASTPIN (-5600 2250) $PN 2
J 0
(-5615 2265);
DISPLAY 0.617021 (-5615 2265);
PAINT MONO (-5615 2265);
FORCEPROP 2 LAST CDS_LIB pure_quanta
J 0
(-5700 2250);
DISPLAY INVISIBLE (-5700 2250);
FORCEPROP 1 LAST PATH I35
J 0
(-5700 2450);
DISPLAY 0.978723 (-5700 2450);
PAINT WHITE (-5700 2450);
DISPLAY INVISIBLE (-5700 2450);
FORCEPROP 2 LAST $SEC 1
J 0
(-5700 2500);
DISPLAY 0.680851 (-5700 2500);
PAINT MONO (-5700 2500);
DISPLAY INVISIBLE (-5700 2500);
FORCEPROP 2 LAST CDS_SEC 1
J 0
(-5700 2500);
DISPLAY 1.021277 (-5700 2500);
DISPLAY INVISIBLE (-5700 2500);
FORCEADD Q_CAP..2
(-6175 3750);
FORCEPROP 1 LAST PART_NUMBER TMP_QCH21006JB10
J 1
(-6175 3800);
DISPLAY 0.510638 (-6175 3800);
DISPLAY INVISIBLE (-6175 3800);
FORCEPROP 1 LAST MATERIAL X7R
J 0
(-6075 3675);
DISPLAY 0.510638 (-6075 3675);
FORCEPROP 1 LAST PACK_TYPE 0402
J 1
(-6175 3675);
DISPLAY 0.510638 (-6175 3675);
FORCEPROP 1 LAST TOLERANCE 5%
J 2
(-5825 3750);
DISPLAY 0.510638 (-5825 3750);
FORCEPROP 1 LAST VOLTAGE 50V
J 0
(-6375 3675);
DISPLAY 0.510638 (-6375 3675);
FORCEPROP 1 LAST VALUE 1000PF
J 2
(-5900 3750);
DISPLAY 0.510638 (-5900 3750);
FORCEPROP 1 LAST LOCATION C2460
J 1
(-6375 3750);
DISPLAY 0.978723 (-6375 3750);
FORCEPROP 1 LASTPIN (-6275 3750) $PN 1
J 0
(-6285 3765);
DISPLAY 0.787234 (-6285 3765);
PAINT MONO (-6285 3765);
FORCEPROP 1 LASTPIN (-6075 3750) $PN 2
J 0
(-6090 3765);
DISPLAY 0.787234 (-6090 3765);
PAINT MONO (-6090 3765);
FORCEPROP 2 LAST CDS_LIB pure_quanta
J 0
(-6175 3750);
DISPLAY INVISIBLE (-6175 3750);
FORCEPROP 1 LAST PATH I36
J 0
(-6175 3950);
DISPLAY 0.978723 (-6175 3950);
PAINT WHITE (-6175 3950);
DISPLAY INVISIBLE (-6175 3950);
FORCEPROP 0 LAST $SEC 1
J 0
(-6375 3800);
DISPLAY 0.680851 (-6375 3800);
PAINT MONO (-6375 3800);
DISPLAY INVISIBLE (-6375 3800);
FORCEPROP 0 LAST CDS_SEC 1
J 0
(-6375 3800);
DISPLAY 1.021277 (-6375 3800);
DISPLAY INVISIBLE (-6375 3800);
FORCEADD Q_RES..1
(-6175 3875);
FORCEPROP 1 LAST PART_NUMBER CS00002JB13
J 0
(-6250 3925);
DISPLAY 0.617021 (-6250 3925);
PAINT BLUE (-6250 3925);
DISPLAY INVISIBLE (-6250 3925);
FORCEPROP 1 LAST WATTAGE 1/16W
J 2
(-5950 3975);
DISPLAY 0.617021 (-5950 3975);
PAINT SKYBLUE (-5950 3975);
FORCEPROP 1 LAST PACK_TYPE 0402LF
J 0
(-6250 4025);
DISPLAY 0.617021 (-6250 4025);
PAINT SKYBLUE (-6250 4025);
FORCEPROP 1 LAST VALUE 0
J 2
(-6025 3875);
DISPLAY 0.617021 (-6025 3875);
PAINT SKYBLUE (-6025 3875);
FORCEPROP 1 LAST TOLERANCE 5%
J 0
(-6000 3875);
DISPLAY 0.617021 (-6000 3875);
PAINT SKYBLUE (-6000 3875);
FORCEPROP 1 LAST MATERIAL CHIP
J 0
(-6250 3975);
DISPLAY 0.617021 (-6250 3975);
PAINT SKYBLUE (-6250 3975);
FORCEPROP 1 LAST LOCATION R2380
J 0
(-6450 3875);
DISPLAY 0.723404 (-6450 3875);
PAINT AQUA (-6450 3875);
FORCEPROP 1 LASTPIN (-6275 3875) $PN 1
J 0
(-6263 3887);
DISPLAY 0.617021 (-6263 3887);
FORCEPROP 1 LASTPIN (-6075 3875) $PN 2
J 0
(-6113 3887);
DISPLAY 0.617021 (-6113 3887);
FORCEPROP 2 LAST CDS_LIB pure_quanta
J 0
(-6175 3875);
PAINT MONO (-6175 3875);
DISPLAY INVISIBLE (-6175 3875);
FORCEPROP 1 LAST PATH I37
J 0
(-6225 4025);
DISPLAY 0.978723 (-6225 4025);
PAINT WHITE (-6225 4025);
DISPLAY INVISIBLE (-6225 4025);
FORCEPROP 2 LAST $SEC 1
J 0
(-6225 4075);
DISPLAY 0.680851 (-6225 4075);
PAINT MONO (-6225 4075);
DISPLAY INVISIBLE (-6225 4075);
FORCEPROP 2 LAST CDS_SEC 1
J 0
(-6225 4075);
DISPLAY 1.021277 (-6225 4075);
DISPLAY INVISIBLE (-6225 4075);
FORCEADD UNIVERSAL_GND..1
(-5700 3650);
FORCEPROP 3 LASTPIN (-5700 3700) SIG_NAME GND\g
J 0
(-5690 3710);
DISPLAY 0.659574 (-5690 3710);
PAINT MONO (-5690 3710);
DISPLAY INVISIBLE (-5690 3710);
FORCEPROP 1 LAST HDL_POWER GND
J 1
(-5675 3575);
DISPLAY 0.872340 (-5675 3575);
PAINT GREEN (-5675 3575);
DISPLAY INVISIBLE (-5675 3575);
FORCEPROP 2 LAST CDS_LIB logical_power
J 0
(-5700 3650);
PAINT MONO (-5700 3650);
DISPLAY INVISIBLE (-5700 3650);
FORCEPROP 1 LAST PATH I38
J 0
(-5625 3650);
DISPLAY 0.872340 (-5625 3650);
PAINT AQUA (-5625 3650);
DISPLAY INVISIBLE (-5625 3650);
FORCEADD Q_CAP..1
(-5275 2975);
FORCEPROP 1 LAST PART_NUMBER CH4104K1B00
J 0
(-5225 2825);
DISPLAY 0.617021 (-5225 2825);
PAINT BLUE (-5225 2825);
DISPLAY INVISIBLE (-5225 2825);
FORCEPROP 1 LAST PACK_TYPE 0402
J 0
(-5225 2775);
DISPLAY 0.617021 (-5225 2775);
PAINT SKYBLUE (-5225 2775);
FORCEPROP 1 LAST TOLERANCE 10%
J 0
(-5225 2925);
DISPLAY 0.617021 (-5225 2925);
PAINT SKYBLUE (-5225 2925);
FORCEPROP 1 LAST VALUE 0.1UF
J 0
(-5225 3025);
DISPLAY 0.617021 (-5225 3025);
PAINT SKYBLUE (-5225 3025);
FORCEPROP 1 LAST MATERIAL X7R
J 0
(-5225 2875);
DISPLAY 0.617021 (-5225 2875);
PAINT SKYBLUE (-5225 2875);
FORCEPROP 1 LAST VOLTAGE 25V
J 0
(-5225 2975);
DISPLAY 0.617021 (-5225 2975);
PAINT SKYBLUE (-5225 2975);
FORCEPROP 1 LAST LOCATION PC1267
J 0
(-5225 3075);
DISPLAY 0.617021 (-5225 3075);
PAINT AQUA (-5225 3075);
FORCEPROP 1 LASTPIN (-5275 3075) $PN 1
J 0
(-5265 3055);
DISPLAY 0.617021 (-5265 3055);
PAINT MONO (-5265 3055);
FORCEPROP 1 LASTPIN (-5275 2875) $PN 2
J 0
(-5265 2855);
DISPLAY 0.617021 (-5265 2855);
PAINT MONO (-5265 2855);
FORCEPROP 2 LAST CDS_LIB pure_quanta
J 0
(-5275 2975);
DISPLAY INVISIBLE (-5275 2975);
FORCEPROP 1 LAST PATH I39
J 0
(-5225 3125);
DISPLAY 0.978723 (-5225 3125);
PAINT WHITE (-5225 3125);
DISPLAY INVISIBLE (-5225 3125);
FORCEPROP 2 LAST $SEC 1
J 0
(-5225 3175);
DISPLAY 0.680851 (-5225 3175);
PAINT MONO (-5225 3175);
DISPLAY INVISIBLE (-5225 3175);
FORCEPROP 2 LAST CDS_SEC 1
J 0
(-5225 3175);
DISPLAY 1.021277 (-5225 3175);
DISPLAY INVISIBLE (-5225 3175);
FORCEADD OFFPAGE..4
R 2
(-10850 3175);
FORCEPROP 2 LASTPIN (-10800 3175) SIG_NAME FM_PVPP_HBM_CPU1_EN
J 0
(-9160 3185);
DISPLAY 0.617021 (-9160 3185);
FORCEPROP 2 LAST $XR0 214 
J 0
(-11102 3175);
DISPLAY 0.638298 (-11102 3175);
PAINT MONO (-11102 3175);
FORCEPROP 1 LAST COMMENT_BODY TRUE
J 2
(-10825 3075);
DISPLAY 0.872340 (-10825 3075);
PAINT GREEN (-10825 3075);
DISPLAY INVISIBLE (-10825 3075);
FORCEPROP 1 LAST OFFPAGE TRUE
J 2
(-11175 3050);
DISPLAY 0.872340 (-11175 3050);
PAINT GREEN (-11175 3050);
DISPLAY INVISIBLE (-11175 3050);
FORCEPROP 2 LAST CDS_LIB standard
J 0
(-10850 3175);
DISPLAY INVISIBLE (-10850 3175);
FORCEPROP 2 LAST PATH I4
J 0
(-11100 3225);
DISPLAY 1.021277 (-11100 3225);
DISPLAY INVISIBLE (-11100 3225);
FORCEADD Q_CAP..1
(-4850 2975);
FORCEPROP 1 LAST PART_NUMBER CH622KMEA03
J 0
(-4800 2825);
DISPLAY 0.617021 (-4800 2825);
PAINT BLUE (-4800 2825);
DISPLAY INVISIBLE (-4800 2825);
FORCEPROP 1 LAST TOLERANCE 20%
J 0
(-4800 2925);
DISPLAY 0.617021 (-4800 2925);
PAINT SKYBLUE (-4800 2925);
FORCEPROP 1 LAST PACK_TYPE C0805
J 0
(-4800 2775);
DISPLAY 0.617021 (-4800 2775);
PAINT SKYBLUE (-4800 2775);
FORCEPROP 1 LAST VALUE 22UF
J 0
(-4800 3025);
DISPLAY 0.617021 (-4800 3025);
PAINT SKYBLUE (-4800 3025);
FORCEPROP 1 LAST MATERIAL X6S
J 0
(-4800 2875);
DISPLAY 0.617021 (-4800 2875);
PAINT SKYBLUE (-4800 2875);
FORCEPROP 1 LAST VOLTAGE 4V
J 0
(-4800 2975);
DISPLAY 0.617021 (-4800 2975);
PAINT SKYBLUE (-4800 2975);
FORCEPROP 1 LAST LOCATION PC1268
J 0
(-4800 3075);
DISPLAY 0.617021 (-4800 3075);
PAINT AQUA (-4800 3075);
FORCEPROP 1 LASTPIN (-4850 3075) $PN 1
J 0
(-4840 3055);
DISPLAY 0.617021 (-4840 3055);
PAINT MONO (-4840 3055);
FORCEPROP 1 LASTPIN (-4850 2875) $PN 2
J 0
(-4840 2855);
DISPLAY 0.617021 (-4840 2855);
PAINT MONO (-4840 2855);
FORCEPROP 2 LAST CDS_LIB pure_quanta
J 0
(-4850 2975);
DISPLAY INVISIBLE (-4850 2975);
FORCEPROP 2 LAST BOM_COST VR_PCH
J 0
(-4800 3125);
DISPLAY 0.680851 (-4800 3125);
DISPLAY INVISIBLE (-4800 3125);
FORCEPROP 1 LAST PATH I40
J 0
(-4800 3125);
DISPLAY 0.978723 (-4800 3125);
PAINT WHITE (-4800 3125);
DISPLAY INVISIBLE (-4800 3125);
FORCEPROP 2 LAST $SEC 1
J 0
(-4800 3175);
DISPLAY 0.680851 (-4800 3175);
PAINT MONO (-4800 3175);
DISPLAY INVISIBLE (-4800 3175);
FORCEPROP 2 LAST CDS_SEC 1
J 0
(-4800 3175);
DISPLAY 1.021277 (-4800 3175);
DISPLAY INVISIBLE (-4800 3175);
FORCEADD Q_CAP..1
(-4475 2975);
FORCEPROP 1 LAST PART_NUMBER CH622KMEA03
J 0
(-4425 2825);
DISPLAY 0.617021 (-4425 2825);
PAINT BLUE (-4425 2825);
DISPLAY INVISIBLE (-4425 2825);
FORCEPROP 1 LAST VALUE 22UF
J 0
(-4425 3025);
DISPLAY 0.617021 (-4425 3025);
PAINT SKYBLUE (-4425 3025);
FORCEPROP 1 LAST VOLTAGE 4V
J 0
(-4425 2975);
DISPLAY 0.617021 (-4425 2975);
PAINT SKYBLUE (-4425 2975);
FORCEPROP 1 LAST TOLERANCE 20%
J 0
(-4425 2925);
DISPLAY 0.617021 (-4425 2925);
PAINT SKYBLUE (-4425 2925);
FORCEPROP 1 LAST PACK_TYPE C0805
J 0
(-4425 2775);
DISPLAY 0.617021 (-4425 2775);
PAINT SKYBLUE (-4425 2775);
FORCEPROP 1 LAST MATERIAL X6S
J 0
(-4425 2875);
DISPLAY 0.617021 (-4425 2875);
PAINT SKYBLUE (-4425 2875);
FORCEPROP 1 LAST LOCATION PC1269
J 0
(-4425 3075);
DISPLAY 0.617021 (-4425 3075);
PAINT AQUA (-4425 3075);
FORCEPROP 1 LASTPIN (-4475 3075) $PN 1
J 0
(-4465 3055);
DISPLAY 0.617021 (-4465 3055);
PAINT MONO (-4465 3055);
FORCEPROP 1 LASTPIN (-4475 2875) $PN 2
J 0
(-4465 2855);
DISPLAY 0.617021 (-4465 2855);
PAINT MONO (-4465 2855);
FORCEPROP 2 LAST CDS_LIB pure_quanta
J 0
(-4475 2975);
DISPLAY INVISIBLE (-4475 2975);
FORCEPROP 2 LAST BOM_COST VR_PCH
J 0
(-4425 3125);
DISPLAY 0.680851 (-4425 3125);
DISPLAY INVISIBLE (-4425 3125);
FORCEPROP 1 LAST PATH I41
J 0
(-4425 3125);
DISPLAY 0.978723 (-4425 3125);
PAINT WHITE (-4425 3125);
DISPLAY INVISIBLE (-4425 3125);
FORCEPROP 2 LAST $SEC 1
J 0
(-4425 3175);
DISPLAY 0.680851 (-4425 3175);
PAINT MONO (-4425 3175);
DISPLAY INVISIBLE (-4425 3175);
FORCEPROP 2 LAST CDS_SEC 1
J 0
(-4425 3175);
DISPLAY 1.021277 (-4425 3175);
DISPLAY INVISIBLE (-4425 3175);
FORCEADD OFFPAGE..2
(-5025 3875);
FORCEPROP 2 LAST $XR1 254 
J 0
(-4716 3875);
DISPLAY 0.638298 (-4716 3875);
PAINT MONO (-4716 3875);
FORCEPROP 2 LAST $XR0 213 
J 0
(-4836 3875);
DISPLAY 0.638298 (-4836 3875);
PAINT MONO (-4836 3875);
FORCEPROP 1 LAST COMMENT_BODY TRUE
J 0
(-5070 3780);
DISPLAY 0.531915 (-5070 3780);
PAINT GREEN (-5070 3780);
DISPLAY INVISIBLE (-5070 3780);
FORCEPROP 1 LAST OFFPAGE TRUE
J 0
(-4700 3750);
DISPLAY 0.531915 (-4700 3750);
PAINT GREEN (-4700 3750);
DISPLAY INVISIBLE (-4700 3750);
FORCEPROP 2 LAST BOM_COST VR_SYSTEM 
J 0
(-4675 3925);
DISPLAY 0.680851 (-4675 3925);
DISPLAY INVISIBLE (-4675 3925);
FORCEPROP 2 LAST CDS_LIB standard
J 0
(-5025 3875);
PAINT MONO (-5025 3875);
DISPLAY INVISIBLE (-5025 3875);
FORCEPROP 2 LAST PATH I42
J 0
(-4700 3925);
DISPLAY 1.021277 (-4700 3925);
DISPLAY INVISIBLE (-4700 3925);
FORCEADD UNIVERSAL_POWER..1
(-6600 4450);
FORCEPROP 3 LASTPIN (-6600 4400) SIG_NAME P3V3_AUX\g
J 0
(-6590 4410);
DISPLAY 0.659574 (-6590 4410);
PAINT MONO (-6590 4410);
DISPLAY INVISIBLE (-6590 4410);
FORCEPROP 1 LAST HDL_POWER P3V3_AUX
J 1
(-6600 4500);
DISPLAY 0.617021 (-6600 4500);
PAINT GREEN (-6600 4500);
FORCEPROP 2 LAST CDS_LIB logical_power
J 0
(-6600 4450);
DISPLAY INVISIBLE (-6600 4450);
FORCEPROP 1 LAST PATH I43
J 0
(-6550 4475);
DISPLAY 0.872340 (-6550 4475);
PAINT AQUA (-6550 4475);
DISPLAY INVISIBLE (-6550 4475);
FORCEADD Q_SHORT..1
(-3950 1425);
FORCEPROP 1 LAST PART_NUMBER SHORT6
J 0
(-4025 1535);
DISPLAY 0.617021 (-4025 1535);
PAINT BLUE (-4025 1535);
DISPLAY INVISIBLE (-4025 1535);
FORCEPROP 2 LAST PACK_TYPE SM
J 0
(-4025 1625);
DISPLAY 0.617021 (-4025 1625);
PAINT SKYBLUE (-4025 1625);
FORCEPROP 1 LAST MATERIAL EMPTY
J 0
(-4025 1585);
DISPLAY 0.617021 (-4025 1585);
PAINT RED (-4025 1585);
FORCEPROP 1 LAST LOCATION PJ67
J 0
(-4025 1480);
DISPLAY 0.617021 (-4025 1480);
PAINT AQUA (-4025 1480);
FORCEPROP 0 LASTPIN (-4075 1425) $PN 1
J 2
(-4085 1435);
DISPLAY 0.808511 (-4085 1435);
FORCEPROP 0 LASTPIN (-3825 1425) $PN 2
J 0
(-3815 1435);
DISPLAY 0.808511 (-3815 1435);
FORCEPROP 2 LAST BOM_COST VR_PCH
J 0
(-4025 1675);
DISPLAY 0.680851 (-4025 1675);
DISPLAY INVISIBLE (-4025 1675);
FORCEPROP 1 LAST NEEDS_NO_SIZE TRUE
J 0
(-3950 1425);
DISPLAY 0.468085 (-3950 1425);
PAINT GREEN (-3950 1425);
DISPLAY INVISIBLE (-3950 1425);
FORCEPROP 2 LAST CDS_LIB pure_quanta
J 0
(-3950 1425);
DISPLAY INVISIBLE (-3950 1425);
FORCEPROP 1 LAST PATH I44
J 0
(-4025 1630);
DISPLAY 0.723404 (-4025 1630);
PAINT GREEN (-4025 1630);
DISPLAY INVISIBLE (-4025 1630);
FORCEPROP 0 LAST $SEC 1
J 0
(-4025 1675);
DISPLAY INVISIBLE (-4025 1675);
FORCEPROP 0 LAST CDS_SEC 1
J 0
(-4025 1675);
DISPLAY INVISIBLE (-4025 1675);
FORCEADD UNIVERSAL_GND..1
(-3275 1100);
FORCEPROP 3 LASTPIN (-3275 1150) SIG_NAME GND\g
J 0
(-3265 1160);
DISPLAY 0.659574 (-3265 1160);
PAINT MONO (-3265 1160);
DISPLAY INVISIBLE (-3265 1160);
FORCEPROP 1 LAST HDL_POWER GND
J 1
(-3250 1025);
DISPLAY 0.872340 (-3250 1025);
PAINT GREEN (-3250 1025);
DISPLAY INVISIBLE (-3250 1025);
FORCEPROP 2 LAST CDS_LIB logical_power
J 0
(-3275 1100);
DISPLAY INVISIBLE (-3275 1100);
FORCEPROP 1 LAST PATH I45
J 0
(-3200 1100);
DISPLAY 0.872340 (-3200 1100);
PAINT AQUA (-3200 1100);
DISPLAY INVISIBLE (-3200 1100);
FORCEADD Q_SHORT..1
(-3950 2425);
FORCEPROP 1 LAST PART_NUMBER SHORT6
J 0
(-4025 2535);
DISPLAY 0.617021 (-4025 2535);
PAINT BLUE (-4025 2535);
DISPLAY INVISIBLE (-4025 2535);
FORCEPROP 1 LAST MATERIAL EMPTY
J 0
(-4025 2585);
DISPLAY 0.617021 (-4025 2585);
PAINT RED (-4025 2585);
FORCEPROP 2 LAST PACK_TYPE SM
J 0
(-4025 2625);
DISPLAY 0.617021 (-4025 2625);
PAINT SKYBLUE (-4025 2625);
FORCEPROP 1 LAST LOCATION PJ66
J 0
(-4025 2480);
DISPLAY 0.617021 (-4025 2480);
PAINT AQUA (-4025 2480);
FORCEPROP 0 LASTPIN (-4075 2425) $PN 1
J 2
(-4085 2435);
DISPLAY 0.808511 (-4085 2435);
FORCEPROP 0 LASTPIN (-3825 2425) $PN 2
J 0
(-3815 2435);
DISPLAY 0.808511 (-3815 2435);
FORCEPROP 2 LAST BOM_COST VR_PCH
J 0
(-4025 2675);
DISPLAY 0.680851 (-4025 2675);
DISPLAY INVISIBLE (-4025 2675);
FORCEPROP 1 LAST NEEDS_NO_SIZE TRUE
J 0
(-3950 2425);
DISPLAY 0.468085 (-3950 2425);
PAINT GREEN (-3950 2425);
DISPLAY INVISIBLE (-3950 2425);
FORCEPROP 2 LAST CDS_LIB pure_quanta
J 0
(-3950 2425);
DISPLAY INVISIBLE (-3950 2425);
FORCEPROP 1 LAST PATH I46
J 0
(-4025 2630);
DISPLAY 0.723404 (-4025 2630);
PAINT GREEN (-4025 2630);
DISPLAY INVISIBLE (-4025 2630);
FORCEPROP 0 LAST $SEC 1
J 0
(-4025 2675);
DISPLAY INVISIBLE (-4025 2675);
FORCEPROP 0 LAST CDS_SEC 1
J 0
(-4025 2675);
DISPLAY INVISIBLE (-4025 2675);
FORCEADD Q_CAP..1
(-4100 2975);
FORCEPROP 1 LAST PART_NUMBER CH622KMEA03
J 0
(-4050 2825);
DISPLAY 0.617021 (-4050 2825);
PAINT BLUE (-4050 2825);
DISPLAY INVISIBLE (-4050 2825);
FORCEPROP 1 LAST MATERIAL X6S
J 0
(-4050 2875);
DISPLAY 0.617021 (-4050 2875);
PAINT SKYBLUE (-4050 2875);
FORCEPROP 1 LAST TOLERANCE 20%
J 0
(-4050 2925);
DISPLAY 0.617021 (-4050 2925);
PAINT SKYBLUE (-4050 2925);
FORCEPROP 1 LAST VOLTAGE 4V
J 0
(-4050 2975);
DISPLAY 0.617021 (-4050 2975);
PAINT SKYBLUE (-4050 2975);
FORCEPROP 1 LAST VALUE 22UF
J 0
(-4050 3025);
DISPLAY 0.617021 (-4050 3025);
PAINT SKYBLUE (-4050 3025);
FORCEPROP 1 LAST PACK_TYPE C0805
J 0
(-4050 2775);
DISPLAY 0.617021 (-4050 2775);
PAINT SKYBLUE (-4050 2775);
FORCEPROP 1 LAST LOCATION PC1270
J 0
(-4050 3075);
DISPLAY 0.617021 (-4050 3075);
PAINT AQUA (-4050 3075);
FORCEPROP 1 LASTPIN (-4100 3075) $PN 1
J 0
(-4090 3055);
DISPLAY 0.617021 (-4090 3055);
PAINT MONO (-4090 3055);
FORCEPROP 1 LASTPIN (-4100 2875) $PN 2
J 0
(-4090 2855);
DISPLAY 0.617021 (-4090 2855);
PAINT MONO (-4090 2855);
FORCEPROP 2 LAST CDS_LIB pure_quanta
J 0
(-4100 2975);
DISPLAY INVISIBLE (-4100 2975);
FORCEPROP 2 LAST BOM_COST VR_PCH
J 0
(-4050 3125);
DISPLAY 0.680851 (-4050 3125);
DISPLAY INVISIBLE (-4050 3125);
FORCEPROP 1 LAST PATH I47
J 0
(-4050 3125);
DISPLAY 0.978723 (-4050 3125);
PAINT WHITE (-4050 3125);
DISPLAY INVISIBLE (-4050 3125);
FORCEPROP 2 LAST $SEC 1
J 0
(-4050 3175);
DISPLAY 0.680851 (-4050 3175);
PAINT MONO (-4050 3175);
DISPLAY INVISIBLE (-4050 3175);
FORCEPROP 2 LAST CDS_SEC 1
J 0
(-4050 3175);
DISPLAY 1.021277 (-4050 3175);
DISPLAY INVISIBLE (-4050 3175);
FORCEADD UNIVERSAL_GND..1
(-3700 2600);
FORCEPROP 3 LASTPIN (-3700 2650) SIG_NAME GND\g
J 0
(-3690 2660);
DISPLAY 0.659574 (-3690 2660);
PAINT MONO (-3690 2660);
DISPLAY INVISIBLE (-3690 2660);
FORCEPROP 1 LAST HDL_POWER GND
J 1
(-3675 2525);
DISPLAY 0.872340 (-3675 2525);
PAINT GREEN (-3675 2525);
DISPLAY INVISIBLE (-3675 2525);
FORCEPROP 2 LAST CDS_LIB logical_power
J 0
(-3700 2600);
DISPLAY INVISIBLE (-3700 2600);
FORCEPROP 1 LAST PATH I48
J 0
(-3625 2600);
DISPLAY 0.872340 (-3625 2600);
PAINT AQUA (-3625 2600);
DISPLAY INVISIBLE (-3625 2600);
FORCEADD Q_CAPP..1
(-3700 2975);
FORCEPROP 1 LAST PART_NUMBER CC75601MD16
J 0
(-3650 2775);
DISPLAY 0.638298 (-3650 2775);
DISPLAY INVISIBLE (-3650 2775);
FORCEPROP 1 LAST PACK_TYPE THLF
J 0
(-3650 2825);
DISPLAY 0.638298 (-3650 2825);
FORCEPROP 1 LAST MATERIAL OSCON
J 0
(-3650 2875);
DISPLAY 0.638298 (-3650 2875);
FORCEPROP 1 LAST VALUE 560UF
J 0
(-3650 3025);
DISPLAY 0.638298 (-3650 3025);
FORCEPROP 1 LAST TOLERANCE 20%
J 0
(-3650 2975);
DISPLAY 0.638298 (-3650 2975);
FORCEPROP 1 LAST VOLTAGE 6.3V
J 0
(-3650 2925);
DISPLAY 0.638298 (-3650 2925);
FORCEPROP 1 LAST LOCATION PC1771
J 0
(-3650 3075);
DISPLAY 0.638298 (-3650 3075);
FORCEPROP 1 LASTPIN (-3700 3075) $PN 1
J 0
(-3690 3060);
DISPLAY 0.787234 (-3690 3060);
PAINT MONO (-3690 3060);
FORCEPROP 1 LASTPIN (-3700 2875) $PN 2
J 0
(-3690 2860);
DISPLAY 0.787234 (-3690 2860);
PAINT MONO (-3690 2860);
FORCEPROP 2 LAST BOM_COST VR_PCH
J 0
(-3650 3125);
DISPLAY 0.680851 (-3650 3125);
DISPLAY INVISIBLE (-3650 3125);
FORCEPROP 2 LAST CDS_LIB pure_quanta
J 0
(-3700 2975);
DISPLAY INVISIBLE (-3700 2975);
FORCEPROP 1 LAST PATH I49
J 0
(-3650 3125);
DISPLAY 0.978723 (-3650 3125);
DISPLAY INVISIBLE (-3650 3125);
FORCEPROP 0 LAST $SEC 1
J 0
(-3650 3125);
DISPLAY 0.680851 (-3650 3125);
PAINT MONO (-3650 3125);
DISPLAY INVISIBLE (-3650 3125);
FORCEPROP 2 LAST CDS_SEC 1
J 0
(-3650 3175);
DISPLAY 1.021277 (-3650 3175);
DISPLAY INVISIBLE (-3650 3175);
FORCEADD UNIVERSAL_POWER..1
(-10525 2875);
FORCEPROP 3 LASTPIN (-10525 2825) SIG_NAME P3V3_AUX\g
J 0
(-10515 2835);
DISPLAY 0.659574 (-10515 2835);
PAINT MONO (-10515 2835);
DISPLAY INVISIBLE (-10515 2835);
FORCEPROP 1 LAST HDL_POWER P3V3_AUX
J 1
(-10525 2925);
DISPLAY 0.617021 (-10525 2925);
PAINT GREEN (-10525 2925);
FORCEPROP 2 LAST CDS_LIB logical_power
J 0
(-10525 2875);
DISPLAY INVISIBLE (-10525 2875);
FORCEPROP 1 LAST PATH I5
J 0
(-10475 2900);
DISPLAY 0.872340 (-10475 2900);
PAINT AQUA (-10475 2900);
DISPLAY INVISIBLE (-10475 2900);
FORCEADD UNIVERSAL_POWER..1
(-3275 3400);
FORCEPROP 3 LASTPIN (-3275 3350) SIG_NAME PVPP_HBM_CPU1\g
J 0
(-3265 3360);
DISPLAY 0.659574 (-3265 3360);
PAINT MONO (-3265 3360);
DISPLAY INVISIBLE (-3265 3360);
FORCEPROP 1 LAST HDL_POWER PVPP_HBM_CPU1
J 1
(-3275 3450);
DISPLAY 0.617021 (-3275 3450);
PAINT GREEN (-3275 3450);
FORCEPROP 2 LAST CDS_LIB logical_power
J 0
(-3275 3400);
DISPLAY INVISIBLE (-3275 3400);
FORCEPROP 1 LAST PATH I50
J 0
(-3225 3425);
DISPLAY 0.872340 (-3225 3425);
PAINT AQUA (-3225 3425);
DISPLAY INVISIBLE (-3225 3425);
FORCEADD VCCAUX15..1
(-11125 3425);
FORCEPROP 3 LASTPIN (-11125 3375) SIG_NAME P3V3_AUX\g
J 0
(-11115 3385);
DISPLAY 0.659574 (-11115 3385);
PAINT MONO (-11115 3385);
DISPLAY INVISIBLE (-11115 3385);
FORCEPROP 1 LAST HDL_POWER P3V3_AUX
J 1
(-11125 3467);
DISPLAY 0.617021 (-11125 3467);
PAINT GREEN (-11125 3467);
FORCEPROP 2 LAST BOM_COST VR_PCH
J 0
(-11125 3500);
DISPLAY 0.680851 (-11125 3500);
DISPLAY INVISIBLE (-11125 3500);
FORCEPROP 2 LAST CDS_LIB logical_power
J 0
(-11125 3425);
PAINT MONO (-11125 3425);
DISPLAY INVISIBLE (-11125 3425);
FORCEPROP 1 LAST PATH I6
J 0
(-11075 3450);
DISPLAY 0.872340 (-11075 3450);
PAINT AQUA (-11075 3450);
DISPLAY INVISIBLE (-11075 3450);
FORCEADD UNIVERSAL_GND..1
(-10800 3550);
FORCEPROP 3 LASTPIN (-10800 3600) SIG_NAME GND\g
J 0
(-10790 3610);
DISPLAY 0.659574 (-10790 3610);
PAINT MONO (-10790 3610);
DISPLAY INVISIBLE (-10790 3610);
FORCEPROP 1 LAST HDL_POWER GND
J 1
(-10775 3475);
DISPLAY 0.872340 (-10775 3475);
PAINT GREEN (-10775 3475);
DISPLAY INVISIBLE (-10775 3475);
FORCEPROP 2 LAST CDS_LIB logical_power
J 0
(-10800 3550);
PAINT MONO (-10800 3550);
DISPLAY INVISIBLE (-10800 3550);
FORCEPROP 1 LAST PATH I7
J 0
(-10725 3550);
DISPLAY 0.872340 (-10725 3550);
PAINT AQUA (-10725 3550);
DISPLAY INVISIBLE (-10725 3550);
FORCEADD Q_CAP..1
(-10800 3900);
FORCEPROP 1 LAST PART_NUMBER CH6223MEA01
J 0
(-10750 3700);
DISPLAY 0.617021 (-10750 3700);
PAINT BLUE (-10750 3700);
DISPLAY INVISIBLE (-10750 3700);
FORCEPROP 1 LAST MATERIAL X6S
J 0
(-10750 3800);
DISPLAY 0.617021 (-10750 3800);
PAINT SKYBLUE (-10750 3800);
FORCEPROP 1 LAST VALUE 22UF
J 0
(-10750 3950);
DISPLAY 0.617021 (-10750 3950);
PAINT SKYBLUE (-10750 3950);
FORCEPROP 1 LAST VOLTAGE 16V
J 0
(-10750 3900);
DISPLAY 0.617021 (-10750 3900);
PAINT SKYBLUE (-10750 3900);
FORCEPROP 1 LAST PACK_TYPE C0805
J 0
(-10750 3750);
DISPLAY 0.617021 (-10750 3750);
PAINT SKYBLUE (-10750 3750);
FORCEPROP 1 LAST TOLERANCE 20%
J 0
(-10750 3850);
DISPLAY 0.617021 (-10750 3850);
PAINT SKYBLUE (-10750 3850);
FORCEPROP 1 LAST LOCATION PC1259
J 0
(-10750 4000);
DISPLAY 0.617021 (-10750 4000);
PAINT AQUA (-10750 4000);
FORCEPROP 1 LASTPIN (-10800 4000) $PN 1
J 0
(-10790 3980);
DISPLAY 0.617021 (-10790 3980);
PAINT MONO (-10790 3980);
FORCEPROP 1 LASTPIN (-10800 3800) $PN 2
J 0
(-10790 3780);
DISPLAY 0.617021 (-10790 3780);
PAINT MONO (-10790 3780);
FORCEPROP 2 LAST CDS_LIB pure_quanta
J 0
(-10800 3900);
DISPLAY INVISIBLE (-10800 3900);
FORCEPROP 2 LAST BOM_COST VR_PCH
J 0
(-10750 4050);
DISPLAY 0.680851 (-10750 4050);
DISPLAY INVISIBLE (-10750 4050);
FORCEPROP 1 LAST PATH I8
J 0
(-10750 4050);
DISPLAY 0.978723 (-10750 4050);
PAINT WHITE (-10750 4050);
DISPLAY INVISIBLE (-10750 4050);
FORCEPROP 2 LAST $SEC 1
J 0
(-10750 4100);
DISPLAY 0.680851 (-10750 4100);
PAINT MONO (-10750 4100);
DISPLAY INVISIBLE (-10750 4100);
FORCEPROP 2 LAST CDS_SEC 1
J 0
(-10750 4100);
DISPLAY 1.021277 (-10750 4100);
DISPLAY INVISIBLE (-10750 4100);
FORCEADD UNIVERSAL_GND..1
(-9175 1825);
FORCEPROP 3 LASTPIN (-9175 1875) SIG_NAME GND\g
J 0
(-9165 1885);
DISPLAY 0.659574 (-9165 1885);
PAINT MONO (-9165 1885);
DISPLAY INVISIBLE (-9165 1885);
FORCEPROP 1 LAST HDL_POWER GND
J 1
(-9150 1750);
DISPLAY 0.872340 (-9150 1750);
PAINT GREEN (-9150 1750);
DISPLAY INVISIBLE (-9150 1750);
FORCEPROP 2 LAST CDS_LIB logical_power
J 0
(-9175 1825);
DISPLAY INVISIBLE (-9175 1825);
FORCEPROP 1 LAST PATH I9
J 0
(-9100 1825);
DISPLAY 0.872340 (-9100 1825);
PAINT AQUA (-9100 1825);
DISPLAY INVISIBLE (-9100 1825);
FORCEADD DNS..2
(-9750 2925);
PAINT RED (-9750 2925);
FORCEPROP 1 LAST COMMENT_BODY TRUE
R 1
J 0
(-9675 2700);
DISPLAY 0.872340 (-9675 2700);
PAINT GREEN (-9675 2700);
DISPLAY INVISIBLE (-9675 2700);
FORCEPROP 2 LAST CDS_LIB mstr_misc
J 0
(-9750 2925);
PAINT MONO (-9750 2925);
DISPLAY INVISIBLE (-9750 2925);
FORCEADD DNS..2
(-10300 3350);
PAINT RED (-10300 3350);
FORCEPROP 1 LAST COMMENT_BODY TRUE
R 1
J 0
(-10225 3125);
DISPLAY 0.872340 (-10225 3125);
PAINT GREEN (-10225 3125);
DISPLAY INVISIBLE (-10225 3125);
FORCEPROP 2 LAST CDS_LIB mstr_misc
J 0
(-10300 3350);
PAINT MONO (-10300 3350);
DISPLAY INVISIBLE (-10300 3350);
FORCEADD DNS..2
(-5650 1750);
PAINT RED (-5650 1750);
FORCEPROP 2 LAST CDS_LIB mstr_misc
J 0
(-5650 1750);
DISPLAY INVISIBLE (-5650 1750);
FORCEPROP 1 LAST COMMENT_BODY TRUE
R 1
J 0
(-5575 1525);
DISPLAY 0.872340 (-5575 1525);
PAINT GREEN (-5575 1525);
DISPLAY INVISIBLE (-5575 1525);
FORCEADD DNS..2
(-5675 2050);
PAINT RED (-5675 2050);
FORCEPROP 2 LAST CDS_LIB mstr_misc
J 0
(-5675 2050);
DISPLAY INVISIBLE (-5675 2050);
FORCEPROP 1 LAST COMMENT_BODY TRUE
R 1
J 0
(-5600 1825);
DISPLAY 0.872340 (-5600 1825);
PAINT GREEN (-5600 1825);
DISPLAY INVISIBLE (-5600 1825);
FORCEADD QUANTA_TITLE_BLOCK_C..1
(-2275 -75);
FORCEPROP 0 LAST CDS_CON_LAST_MODIFIED Fri Aug 25 14:05:09 2023
J 0
(-4160 -60);
DISPLAY INVISIBLE (-4160 -60);
FORCEPROP 1 LAST CUSTOM_TXT_CDS <CON_LAST_MODIFIED>
J 0
(-4160 -60);
DISPLAY 0.978723 (-4160 -60);
FORCEPROP 2 LAST CUSTOM_TXT_CDS <XR_PAGE_TITLE>
J 0
(-10165 5175);
DISPLAY 0.638298 (-10165 5175);
PAINT PINK (-10165 5175);
DISPLAY INVISIBLE (-10165 5175);
FORCEPROP 1 LAST CUSTOM_TXT_CDS <NAME_2>
J 0
(-5450 -25);
FORCEPROP 1 LAST CUSTOM_TXT_CDS <NAME_1>
J 0
(-5450 100);
FORCEPROP 1 LAST CUSTOM_TXT_CDS <Q_NUMBER>
J 0
(-3678 28);
DISPLAY 1.212766 (-3678 28);
FORCEPROP 1 LAST CUSTOM_TXT_CDS <Q_PROJ>
J 0
(-4657 27);
DISPLAY 1.212766 (-4657 27);
FORCEPROP 1 LAST CUSTOM_TXT_CDS <Q_REV>
J 0
(-2459 28);
DISPLAY 1.212766 (-2459 28);
FORCEPROP 1 LAST CUSTOM_TXT_CDS <CON_PAGE_NUM> OF <CON_TOTAL_PAGES>
J 0
(-2721 -57);
DISPLAY 0.978723 (-2721 -57);
FORCEPROP 1 LAST Q_TITLE PVPP_HBM_CPU1
J 0
(-11575 -25);
DISPLAY 2.446809 (-11575 -25);
PAINT GREEN (-11575 -25);
FORCEPROP 1 LAST Q_DEPT 
J 1
(-6038 -26);
DISPLAY 1.957447 (-6038 -26);
PAINT GREEN (-6038 -26);
FORCEPROP 2 LAST CDS_XR_PAGE_TITLE CR-299 : @S9S_MB_2U_LIB.S9S_MB_2U(SCH_1):PAGE299
J 0
(-10165 5175);
DISPLAY 0.638298 (-10165 5175);
PAINT PINK (-10165 5175);
DISPLAY INVISIBLE (-10165 5175);
FORCEPROP 1 LAST CDS_LMAN_SYM_OUTLINE -9475,6775,100,-125
J 0
(-2275 -75);
DISPLAY 0.468085 (-2275 -75);
PAINT GREEN (-2275 -75);
DISPLAY INVISIBLE (-2275 -75);
FORCEPROP 2 LAST CDS_LIB pure_quanta
J 0
(-2275 -75);
DISPLAY INVISIBLE (-2275 -75);
FORCEPROP 2 LAST PAGE_BORDER TRUE
J 0
(-10165 5175);
DISPLAY 0.638298 (-10165 5175);
PAINT PINK (-10165 5175);
DISPLAY INVISIBLE (-10165 5175);
FORCEPROP 1 LAST COMMENT_BODY TRUE
J 0
(-2263 -88);
DISPLAY 0.978723 (-2263 -88);
PAINT GREEN (-2263 -88);
DISPLAY INVISIBLE (-2263 -88);
WIRE 16 -1 (-10525 2750)(-10525 2825);
WIRE 16 -1 (-11125 3375)(-11125 3350);
WIRE 16 -1 (-10800 4150)(-10800 4300);
WIRE 16 -1 (-10350 4150)(-10800 4150);
WIRE 16 -1 (-10800 4000)(-10800 4150);
WIRE 16 -1 (-6600 4300)(-6600 4400);
WIRE 16 -1 (-3275 3175)(-3275 3350);
WIRE 16 -1 (-3275 3175)(-3700 3175);
WIRE 16 -1 (-3275 3175)(-3275 2425);
WIRE 16 -1 (-10525 2100)(-10525 1975);
WIRE 16 -1 (-10800 3675)(-10800 3600);
WIRE 16 -1 (-10350 3675)(-10800 3675);
WIRE 16 -1 (-10800 3800)(-10800 3675);
WIRE 16 -1 (-9175 1975)(-9175 1875);
WIRE 16 -1 (-9750 2775)(-9650 2775);
WIRE 16 -1 (-9750 2850)(-9750 2775);
WIRE 16 -1 (-9650 2850)(-9650 2775);
WIRE 16 -1 (-8525 2850)(-8525 2900);
WIRE 16 -1 (-7500 2075)(-7500 2325);
WIRE 16 -1 (-7350 2025)(-7350 1925);
WIRE 16 -1 (-5700 3750)(-5700 3700);
WIRE 16 -1 (-6075 3750)(-5700 3750);
WIRE 16 -1 (-3275 1150)(-3275 1425);
WIRE 16 -1 (-3700 2750)(-3700 2650);
WIRE 16 -1 (-3700 2750)(-4100 2750);
WIRE 16 -1 (-3700 2750)(-3700 2875);
WIRE 16 -1 (-3275 2425)(-3825 2425);
WIRE 16 -1 (-3700 3075)(-3700 3175);
WIRE 16 -1 (-4100 3075)(-4100 3175);
WIRE 16 -1 (-3700 3175)(-4100 3175);
WIRE 16 -1 (-4475 3075)(-4475 3175);
WIRE 16 -1 (-4475 3175)(-4100 3175);
WIRE 16 -1 (-4850 3075)(-4850 3175);
WIRE 16 -1 (-4850 3175)(-4475 3175);
WIRE 16 -1 (-5275 3075)(-5275 3175);
WIRE 16 -1 (-5275 3175)(-4850 3175);
WIRE 16 -1 (-5800 3175)(-5275 3175);
WIRE 16 -1 (-4100 2750)(-4100 2875);
WIRE 16 -1 (-4475 2875)(-4475 2750);
WIRE 16 -1 (-4475 2750)(-4100 2750);
WIRE 16 -1 (-4850 2875)(-4850 2750);
WIRE 16 -1 (-4850 2750)(-4475 2750);
WIRE 16 -1 (-5275 2750)(-4850 2750);
WIRE 16 -1 (-5275 2875)(-5275 2750);
WIRE 16 -1 (-3275 1425)(-3825 1425);
WIRE 16 2175 (-4453 5294)(-2575 5294);
WIRE 16 2175 (-2575 6325)(-2575 5294);
WIRE 16 2175 (-4453 6325)(-4453 5294);
WIRE 16 2175 (-4453 6325)(-2575 6325);
WIRE 16 -1 (-5075 3875)(-6075 3875);
FORCEPROP 2 LAST SIG_NAME PWRGD_PVPP_HBM_CPU1
J 0
(-5760 3885);
DISPLAY 0.617021 (-5760 3885);
WIRE 16 -1 (-5225 2250)(-5600 2250);
WIRE 16 -1 (-5600 2425)(-5225 2425);
WIRE 16 -1 (-5225 2425)(-5225 2250);
WIRE 16 -1 (-4400 2425)(-4400 2025);
WIRE 16 -1 (-4400 2425)(-5225 2425);
FORCEPROP 2 LAST SIG_NAME SH_PVPP_HBM_CPU1_P
J 0
(-5210 2435);
DISPLAY 0.808511 (-5210 2435);
WIRE 16 -1 (-4075 2425)(-4400 2425);
WIRE 16 -1 (-6075 2025)(-5800 2025);
WIRE 16 -1 (-6075 2250)(-6075 2025);
WIRE 16 -1 (-6075 2250)(-5800 2250);
WIRE 16 -1 (-6075 2425)(-6075 2250);
WIRE 16 -1 (-5800 2425)(-6075 2425);
WIRE 16 -1 (-6375 2100)(-6375 2425);
WIRE 16 -1 (-6375 2425)(-6075 2425);
WIRE 16 -1 (-6375 2425)(-6375 2725);
WIRE 16 -1 (-7600 2725)(-6375 2725);
FORCEPROP 2 LAST SIG_NAME PVPP_HBM_CPU1_FB
J 0
(-7410 2735);
DISPLAY 0.638298 (-7410 2735);
WIRE 16 -1 (-4925 1700)(-5525 1700);
FORCEPROP 2 LAST SIG_NAME FM_HBM2_HBM3_VPP_SEL
J 0
(-5485 1710);
DISPLAY 0.617021 (-5485 1710);
WIRE 16 -1 (-5600 2025)(-5325 2025);
FORCEPROP 2 LAST SIG_NAME FM_HBM_VPP_SEL_CPU1_D
J 0
(-5510 1910);
DISPLAY 0.617021 (-5510 1910);
WIRE 16 -1 (-5325 1950)(-5325 2025);
WIRE 16 -1 (-5675 1950)(-5325 1950);
WIRE 16 -1 (-5675 1900)(-5675 1950);
WIRE 16 -1 (-4400 1825)(-4400 1425);
WIRE 16 -1 (-4400 1425)(-4075 1425);
WIRE 16 -1 (-5675 1600)(-5675 1425);
WIRE 16 -1 (-5675 1425)(-4400 1425);
FORCEPROP 2 LAST SIG_NAME SH_PVPP_HBM_CPU1_N
J 0
(-5235 1435);
DISPLAY 0.808511 (-5235 1435);
WIRE 16 -1 (-7600 2575)(-6450 2575);
WIRE 16 -1 (-6375 1900)(-6375 1425);
WIRE 16 -1 (-6375 1425)(-5675 1425);
WIRE 16 -1 (-6450 1425)(-6375 1425);
WIRE 16 -1 (-6450 2575)(-6450 1425);
WIRE 16 -1 (-6850 1425)(-6450 1425);
WIRE 16 -1 (-6850 1900)(-6850 1425);
WIRE 16 -1 (-6500 3750)(-6275 3750);
WIRE 16 -1 (-6500 3875)(-6500 3750);
WIRE 16 -1 (-6275 3875)(-6500 3875);
WIRE 16 -1 (-6500 3875)(-6600 3875);
WIRE 16 -1 (-6600 4100)(-6600 3875);
WIRE 16 -1 (-6600 3875)(-7525 3875);
FORCEPROP 0 LAST CDS_PHYS_NET_NAME PWRGD_PVPP_HBM_CPU1_R
J 0
(-7210 3915);
PAINT MONO (-7210 3915);
DISPLAY INVISIBLE (-7210 3915);
FORCEPROP 2 LAST SIG_NAME PWRGD_PVPP_HBM_CPU1_R
J 0
(-7435 3885);
DISPLAY 0.617021 (-7435 3885);
WIRE 16 -1 (-7525 3675)(-7525 3875);
WIRE 16 -1 (-7600 3675)(-7525 3675);
WIRE 16 -1 (-6725 3300)(-6725 3175);
WIRE 16 -1 (-6725 3175)(-6000 3175);
WIRE 16 -1 (-7600 3175)(-6725 3175);
FORCEPROP 2 LAST SIG_NAME SW_PVPP_HBM_CPU1_SW
J 0
(-7435 3185);
DISPLAY 0.617021 (-7435 3185);
WIRE 16 -1 (-7600 2475)(-7350 2475);
FORCEPROP 2 LAST SIG_NAME PVPP_HBM_CPU1_REF
J 0
(-7410 2485);
DISPLAY 0.617021 (-7410 2485);
WIRE 16 -1 (-7350 2225)(-7350 2475);
WIRE 16 -1 (-7350 2475)(-6850 2475);
WIRE 16 -1 (-6850 2475)(-6850 2100);
WIRE 16 -1 (-6725 3500)(-6725 3575);
WIRE 16 -1 (-7525 3575)(-6725 3575);
FORCEPROP 2 LAST SIG_NAME SW_PVPP_HBM_CPU1_BST
J 0
(-7435 3585);
DISPLAY 0.617021 (-7435 3585);
WIRE 16 -1 (-7525 3575)(-7525 3475);
WIRE 16 -1 (-7525 3475)(-7600 3475);
WIRE 16 -1 (-7600 2325)(-7500 2325);
WIRE 16 -1 (-7500 2375)(-7500 2325);
WIRE 16 -1 (-7600 2375)(-7500 2375);
WIRE 16 -1 (-8400 3625)(-8575 3625);
WIRE 16 -1 (-8575 3675)(-8575 3625);
WIRE 16 -1 (-8400 3675)(-8575 3675);
WIRE 16 -1 (-8575 3675)(-8575 4150);
WIRE 16 -1 (-9500 4150)(-9500 4000);
WIRE 16 -1 (-9500 4150)(-8575 4150);
WIRE 16 -1 (-9925 4000)(-9925 4150);
WIRE 16 -1 (-9500 4150)(-9925 4150);
WIRE 16 -1 (-9925 4150)(-10350 4150);
WIRE 16 -1 (-10350 4000)(-10350 4150);
WIRE 16 -1 (-8525 2900)(-8850 2900);
WIRE 16 -1 (-8400 2975)(-9250 2975);
FORCEPROP 2 LAST SIG_NAME PVPP_HBM_CPU1_MODE
J 0
(-9160 2985);
DISPLAY 0.638298 (-9160 2985);
WIRE 16 -1 (-9250 2900)(-9250 2975);
WIRE 16 -1 (-9050 2900)(-9250 2900);
WIRE 16 -1 (-8400 2725)(-9300 2725);
FORCEPROP 2 LAST SIG_NAME PVPP_HBM_CPU1_VCC
J 0
(-9160 2735);
DISPLAY 0.617021 (-9160 2735);
WIRE 16 -1 (-9300 2725)(-9300 2400);
WIRE 16 -1 (-10525 2550)(-10525 2400);
WIRE 16 -1 (-9300 2400)(-10525 2400);
WIRE 16 -1 (-10525 2300)(-10525 2400);
WIRE 16 -1 (-10350 3800)(-10350 3675);
WIRE 16 -1 (-9925 3675)(-10350 3675);
WIRE 16 -1 (-9925 3800)(-9925 3675);
WIRE 16 -1 (-9500 3675)(-9925 3675);
WIRE 16 -1 (-9500 3800)(-9500 3675);
WIRE 16 -1 (-9625 3350)(-10225 3350);
WIRE 16 -1 (-9625 3175)(-9625 3350);
WIRE 16 -1 (-9625 3175)(-8400 3175);
WIRE 16 -1 (-10800 3175)(-9650 3175);
WIRE 16 -1 (-9650 3175)(-9625 3175);
WIRE 16 -1 (-9650 3050)(-9650 3100);
WIRE 16 -1 (-9650 3100)(-9650 3175);
WIRE 16 -1 (-9750 3100)(-9650 3100);
WIRE 16 -1 (-9750 3050)(-9750 3100);
WIRE 16 -1 (-9175 2375)(-9175 2175);
WIRE 16 -1 (-8400 2375)(-9175 2375);
FORCEPROP 2 LAST SIG_NAME PVPP_HBM_CPU1_CS
J 0
(-9160 2385);
DISPLAY 0.617021 (-9160 2385);
WIRE 16 2175 (-10347 825)(-10347 400);
WIRE 16 2175 (-11200 400)(-10347 400);
WIRE 16 2175 (-11200 825)(-10347 825);
WIRE 16 2175 (-11200 825)(-11200 400);
WIRE 16 -1 (-11125 3350)(-10425 3350);
DOT 1 (-3275 3175);
DOT 1 (-3700 3175);
DOT 1 (-3700 2750);
DOT 1 (-4100 3175);
DOT 1 (-4100 2750);
CIRCLE (-3950 2475)(-3737 2475);
PAINT YELLOW (-3950 2475);
CIRCLE (-3950 1475)(-3720 1475);
PAINT YELLOW (-3950 1475);
DOT 1 (-4475 3175);
DOT 1 (-4475 2750);
DOT 1 (-4850 3175);
DOT 1 (-4850 2750);
DOT 1 (-4400 2425);
DOT 1 (-5275 3175);
DOT 1 (-5225 2425);
DOT 1 (-6075 2250);
DOT 1 (-6075 2425);
DOT 1 (-6375 2425);
DOT 1 (-4400 1425);
DOT 1 (-5675 1425);
DOT 1 (-6375 1425);
DOT 1 (-6500 3875);
DOT 1 (-6600 3875);
DOT 1 (-6725 3175);
DOT 1 (-7350 2475);
DOT 1 (-7500 2325);
DOT 1 (-6450 1425);
DOT 1 (-8575 3675);
DOT 1 (-9500 4150);
DOT 1 (-9925 4150);
DOT 1 (-9925 3675);
DOT 1 (-10350 4150);
DOT 1 (-10350 3675);
DOT 1 (-9625 3175);
DOT 1 (-9650 3175);
DOT 1 (-9650 3100);
DOT 1 (-10800 4150);
DOT 1 (-10800 3675);
DOT 1 (-10525 2400);
FORCENOTE
PLACE AT CHIPSET SIDE
(-4075 1925) 0;
DISPLAY LEFT (-4075 1925);
DISPLAY 1.021277 (-4075 1925);
FORCENOTE
REMOTE SENSE
(-4075 2000) 0;
DISPLAY LEFT (-4075 2000);
DISPLAY 1.021277 (-4075 2000);
FORCENOTE
20220804 CHANGE PC1266 TO 680PF FOR TRANSIENT RESPONSE
(-7800 400) 0;
DISPLAY LEFT (-7800 400);
DISPLAY 1.595745 (-7800 400);
PAINT PINK (-7800 400);
FORCENOTE
CURRENT STEP=4.6A
(-4439 5561) 0;
DISPLAY LEFT (-4439 5561);
DISPLAY 1.170213 (-4439 5561);
PAINT RED (-4439 5561);
FORCENOTE
WORK FREQUENCY=800KHZ
(-4428 5419) 0;
DISPLAY LEFT (-4428 5419);
DISPLAY 1.170213 (-4428 5419);
PAINT WHITE (-4428 5419);
FORCENOTE
SLEW RATE=1.6A/US
(-4439 5486) 0;
DISPLAY LEFT (-4439 5486);
DISPLAY 1.170213 (-4439 5486);
PAINT RED (-4439 5486);
FORCENOTE
TDC=4A
(-4439 5786) 0;
DISPLAY LEFT (-4439 5786);
DISPLAY 1.170213 (-4439 5786);
PAINT WHITE (-4439 5786);
FORCENOTE
MAX CURRENT=5A
(-4439 5711) 0;
DISPLAY LEFT (-4439 5711);
DISPLAY 1.170213 (-4439 5711);
PAINT RED (-4439 5711);
FORCENOTE
VOUT=2.5V
(-4440 6090) 0;
DISPLAY LEFT (-4440 6090);
DISPLAY 1.170213 (-4440 6090);
PAINT WHITE (-4440 6090);
FORCENOTE
DC=+/-0.7%
(-4428 6019) 0;
DISPLAY LEFT (-4428 6019);
DISPLAY 1.276596 (-4428 6019);
PAINT RED (-4428 6019);
FORCENOTE
RIPPLE=+/-7MV
(-4440 5940) 0;
DISPLAY LEFT (-4440 5940);
DISPLAY 1.170213 (-4440 5940);
PAINT RED (-4440 5940);
FORCENOTE
OCP(IMAX*130%)=8A
(-4439 5636) 0;
DISPLAY LEFT (-4439 5636);
DISPLAY 1.170213 (-4439 5636);
PAINT WHITE (-4439 5636);
FORCENOTE
PVPP_HBM_CPU1 SPECIFICATION
(-4440 6240) 0;
DISPLAY LEFT (-4440 6240);
DISPLAY 1.468085 (-4440 6240);
PAINT WHITE (-4440 6240);
FORCENOTE
TOTAL TOL=2.708VMAX/ 2.530VMIN
(-4437 5861) 0;
DISPLAY LEFT (-4437 5861);
DISPLAY 1.276596 (-4437 5861);
PAINT RED (-4437 5861);
FORCENOTE
20220808 UPDATE PDG REV 1.6
(-4600 5150) 0;
DISPLAY LEFT (-4600 5150);
DISPLAY 1.595745 (-4600 5150);
FORCENOTE
PDG REV 1.6
(-4428 5344) 0;
DISPLAY LEFT (-4428 5344);
DISPLAY 1.170213 (-4428 5344);
PAINT WHITE (-4428 5344);
FORCENOTE
RA
(-5850 2650) 0;
DISPLAY LEFT (-5850 2650);
DISPLAY 1.021277 (-5850 2650);
FORCENOTE
PCMC063T-R68MN
(-6050 3075) 0;
DISPLAY LEFT (-6050 3075);
DISPLAY 0.808511 (-6050 3075);
FORCENOTE
6.5*6.9*3.0
(-6050 3025) 0;
DISPLAY LEFT (-6050 3025);
DISPLAY 0.808511 (-6050 3025);
FORCENOTE
ISAT=23A@100C
(-6050 2975) 0;
DISPLAY LEFT (-6050 2975);
DISPLAY 0.808511 (-6050 2975);
FORCENOTE
DCR=5.5M OHM
(-6050 2925) 0;
DISPLAY LEFT (-6050 2925);
DISPLAY 0.808511 (-6050 2925);
FORCENOTE
RB
(-6325 2225) 0;
DISPLAY LEFT (-6325 2225);
DISPLAY 1.021277 (-6325 2225);
FORCENOTE
PC1266 MAIN 680PF
(-5925 1025) 0;
DISPLAY LEFT (-5925 1025);
DISPLAY 1.276596 (-5925 1025);
PAINT PINK (-5925 1025);
FORCENOTE
2ND 270PF
(-5450 925) 0;
DISPLAY LEFT (-5450 925);
DISPLAY 1.276596 (-5450 925);
PAINT PINK (-5450 925);
FORCENOTE
3RD 100PF
(-5450 825) 0;
DISPLAY LEFT (-5450 825);
DISPLAY 1.276596 (-5450 825);
PAINT PINK (-5450 825);
FORCENOTE
VOUT=((RA/RB)+1)*0.6=2.634V
(-6725 1275) 0;
DISPLAY LEFT (-6725 1275);
DISPLAY 1.021277 (-6725 1275);
PAINT SKYBLUE (-6725 1275);
FORCENOTE
20220808 ADD CHANGE LIST
(-6625 1125) 0;
DISPLAY LEFT (-6625 1125);
DISPLAY 1.595745 (-6625 1125);
PAINT PINK (-6625 1125);
FORCENOTE
PVPP_HBM_CPU1
(-8975 4950) 0;
DISPLAY LEFT (-8975 4950);
DISPLAY 3.148936 (-8975 4950);
PAINT YELLOW (-8975 4950);
FORCENOTE
2ND 2.2UF
(-10250 1575) 0;
DISPLAY LEFT (-10250 1575);
DISPLAY 1.276596 (-10250 1575);
PAINT PINK (-10250 1575);
FORCENOTE
3RD 1UF
(-10250 1475) 0;
DISPLAY LEFT (-10250 1475);
DISPLAY 1.276596 (-10250 1475);
PAINT PINK (-10250 1475);
FORCENOTE
20220804 CHANGE IC TABLE
(-11175 275) 0;
DISPLAY LEFT (-11175 275);
DISPLAY 1.595745 (-11175 275);
PAINT PINK (-11175 275);
FORCENOTE
2ND AL000548006
(-11150 550) 0;
DISPLAY LEFT (-11150 550);
DISPLAY 1.021277 (-11150 550);
PAINT WHITE (-11150 550);
FORCENOTE
1ST AL053318002
(-11150 625) 0;
DISPLAY LEFT (-11150 625);
DISPLAY 1.021277 (-11150 625);
PAINT WHITE (-11150 625);
FORCENOTE
3RD AL008633007
(-11150 475) 0;
DISPLAY LEFT (-11150 475);
DISPLAY 1.021277 (-11150 475);
PAINT WHITE (-11150 475);
FORCENOTE
20220808 ADD CHANGE LIST
(-11375 1775) 0;
DISPLAY LEFT (-11375 1775);
DISPLAY 1.595745 (-11375 1775);
PAINT PINK (-11375 1775);
FORCENOTE
PC644 MAIN 1UF
(-10675 1675) 0;
DISPLAY LEFT (-10675 1675);
DISPLAY 1.276596 (-10675 1675);
PAINT PINK (-10675 1675);
FORCENOTE
IC TABLE
(-11175 725) 0;
DISPLAY LEFT (-11175 725);
DISPLAY 1.170213 (-11175 725);
PAINT WHITE (-11175 725);
QUIT
